G04 ================== begin FILE IDENTIFICATION RECORD ==================*
G04 Layout Name:  9052_F0T_PDB_Converter_Brick_F_V03_1208_1600.brd*
G04 Film Name:    top*
G04 File Format:  Gerber RS274X*
G04 File Origin:  Cadence Allegro 17.2-S081*
G04 Origin Date:  Wed Dec 21 09:54:58 2022*
G04 *
G04 Layer:  DRAWING FORMAT/TITLE_BLOCK_A*
G04 Layer:  PIN/SPECIAL_DRILL*
G04 Layer:  DRAWING FORMAT/TITLE_BLOCK*
G04 Layer:  VIA CLASS/TOP*
G04 Layer:  PIN/TOP*
G04 Layer:  MANUFACTURING/PHOTOPLOT_OUTLINE*
G04 Layer:  ETCH/TOP*
G04 Layer:  DRAWING FORMAT/TITLE_DATA_TOP*
G04 *
G04 Offset:    (0.00 0.00)*
G04 Mirror:    No*
G04 Mode:      Positive*
G04 Rotation:  0*
G04 FullContactRelief:  No*
G04 UndefLineWidth:     6.00*
G04 ================== end FILE IDENTIFICATION RECORD ====================*
%FSLAX25Y25*MOIN*%
%IR0*IPPOS*OFA0.00000B0.00000*MIA0B0*SFA1.00000B1.00000*%
%ADD85R,.122X.052*%
%ADD10C,.02*%
%AMMACRO88*
4,1,8,.16634,.20866,
.07776,.20866,
.07776,.14764,
-.16634,.14764,
-.16634,-.14764,
.07776,-.14764,
.07776,-.20866,
.16634,-.20866,
.16634,.20866,
0.0*
%
%ADD88MACRO88*%
%ADD20C,.03*%
%ADD13O,1.26X.394*%
%ADD96R,.13X.095*%
%AMMACRO79*
4,1,5,.07185,-.1063,
-.07185,-.1063,
-.07185,.09252,
-.05807,.1063,
.07185,.1063,
.07185,-.1063,
0.0*
%
%ADD79MACRO79*%
%ADD16C,.05*%
%AMMACRO12*
4,1,41,.45275,-.05906,
.463006,-.058163,
.47295,-.055498,
.48228,-.051147,
.490713,-.045243,
.497993,-.037963,
.503897,-.02953,
.508248,-.0202,
.510913,-.010256,
.51181,0.0,
.510913,.010256,
.508248,.0202,
.503897,.02953,
.497993,.037963,
.490713,.045243,
.48228,.051147,
.47295,.055498,
.463006,.058163,
.45275,.05906,
.33464,.05906,
-.4082,.09829,
-.425347,.097699,
-.442131,.09414,
-.458041,.08772,
-.472595,.078635,
-.485351,.06716,
-.49592,.053645,
-.503981,.0385,
-.509291,.022185,
-.511686,.005196,
-.511095,-.011951,
-.507536,-.028734,
-.501116,-.044645,
-.492031,-.059199,
-.480557,-.071954,
-.467041,-.082523,
-.451896,-.090585,
-.435582,-.095894,
-.418593,-.09829,
-.4082,-.09829,
.33464,-.05906,
.45275,-.05906,
0.0*
%
%ADD12MACRO12*%
%ADD49C,.06*%
%ADD45C,.052*%
%ADD42C,.062*%
%ADD95R,.059X.134*%
%ADD89R,.099X.13*%
%ADD29C,.018*%
%ADD68R,.0848X.13*%
%ADD78C,.066*%
%ADD52C,.06015*%
%ADD46C,.093*%
%ADD43C,.039*%
%ADD17R,.05X.05*%
%ADD69C,.085*%
%ADD50R,.06X.06*%
%ADD15C,.058*%
%ADD41R,.062X.062*%
%ADD14C,.087*%
%ADD77R,.066X.066*%
%ADD53R,.06015X.06015*%
%ADD51R,.093X.093*%
%AMMACRO33*
4,1,28,-.00748,-.00052,
-.00984,-.00052,
-.00984,-.00603,
-.009782,-.006705,
-.009607,-.007359,
-.009321,-.007974,
-.008933,-.008529,
-.008455,-.009009,
-.0079,-.009398,
-.007286,-.009685,
-.006632,-.009861,
-.005957,-.00992,
-.00591,-.00992,
.00591,-.00992,
.006585,-.009869,
.007242,-.009701,
.007859,-.009421,
.008418,-.009039,
.008903,-.008565,
.009297,-.008015,
.009591,-.007404,
.009773,-.006751,
.00984,-.006077,
.00984,-.00603,
.00984,-.00052,
.00748,-.00052,
.00748,.00991,
-.00748,.00991,
-.00748,-.00052,
0.0*
%
%ADD33MACRO33*%
%AMMACRO67*
4,1,5,.01378,.00098,
.01378,-.00492,
-.01378,-.00492,
-.01378,.00492,
.00984,.00492,
.01378,.00098,
0.0*
%
%ADD67MACRO67*%
%AMMACRO61*
4,1,5,.00098,-.01378,
-.00492,-.01378,
-.00492,.01378,
.00492,.01378,
.00492,-.00984,
.00098,-.01378,
0.0*
%
%ADD61MACRO61*%
%AMMACRO31*
4,1,28,-.00052,.00748,
-.00052,.00984,
-.00603,.00984,
-.006705,.009782,
-.007359,.009607,
-.007974,.009321,
-.008529,.008933,
-.009009,.008455,
-.009398,.0079,
-.009685,.007286,
-.009861,.006632,
-.00992,.005957,
-.00992,.00591,
-.00992,-.00591,
-.009869,-.006585,
-.009701,-.007242,
-.009421,-.007859,
-.009039,-.008418,
-.008565,-.008903,
-.008015,-.009297,
-.007404,-.009591,
-.006751,-.009773,
-.006077,-.00984,
-.00603,-.00984,
-.00052,-.00984,
-.00052,-.00748,
.00991,-.00748,
.00991,.00748,
-.00052,.00748,
0.0*
%
%ADD31MACRO31*%
%AMMACRO32*
4,1,28,-.00748,.00051,
-.00984,.00051,
-.00984,.00602,
-.009782,.006695,
-.009607,.007349,
-.009321,.007964,
-.008933,.008519,
-.008455,.008998,
-.0079,.009388,
-.007287,.009675,
-.006632,.009851,
-.005958,.00991,
-.00591,.00991,
.00591,.00991,
.006585,.009859,
.007242,.009691,
.007859,.009411,
.008418,.009029,
.008903,.008555,
.009297,.008005,
.00959,.007394,
.009773,.006742,
.00984,.006068,
.00984,.00602,
.00984,.00051,
.00748,.00051,
.00748,-.00992,
-.00748,-.00992,
-.00748,.00051,
0.0*
%
%ADD32MACRO32*%
%AMMACRO65*
4,1,5,.01378,-.00098,
.01378,.00492,
-.01378,.00492,
-.01378,-.00492,
.00984,-.00492,
.01378,-.00098,
0.0*
%
%ADD65MACRO65*%
%AMMACRO60*
4,1,5,-.00098,-.01378,
.00492,-.01378,
.00492,.01378,
-.00492,.01378,
-.00492,-.00984,
-.00098,-.01378,
0.0*
%
%ADD60MACRO60*%
%AMMACRO30*
4,1,28,.00051,.00748,
.00051,.00984,
.00602,.00984,
.006695,.009782,
.007349,.009607,
.007964,.009321,
.008519,.008933,
.008998,.008455,
.009388,.0079,
.009675,.007287,
.009851,.006632,
.00991,.005958,
.00991,.00591,
.00991,-.00591,
.009859,-.006585,
.009691,-.007242,
.009411,-.007859,
.009029,-.008418,
.008555,-.008903,
.008005,-.009297,
.007394,-.00959,
.006742,-.009773,
.006068,-.00984,
.00602,-.00984,
.00051,-.00984,
.00051,-.00748,
-.00992,-.00748,
-.00992,.00748,
.00051,.00748,
0.0*
%
%ADD30MACRO30*%
%ADD90R,.11X.22*%
%ADD98R,.01X.02*%
%ADD83R,.03X.011*%
%ADD91O,.033X.012*%
%ADD82R,.011X.03*%
%ADD37R,.05X.01*%
%ADD27R,.032X.01*%
%ADD92O,.012X.033*%
%ADD38R,.01X.032*%
%ADD66R,.052X.01*%
%ADD86R,.032X.022*%
%ADD55R,.05X.04*%
%ADD62R,.036X.01*%
%ADD54R,.04X.05*%
%ADD22R,.02X.018*%
%ADD81R,.028X.011*%
%ADD36R,.018X.02*%
%ADD93C,.4*%
%ADD80R,.011X.028*%
%ADD74R,.063X.04*%
%ADD99R,.126X.27*%
%ADD72R,.04X.063*%
%ADD97R,.135X.128*%
%ADD56R,.032X.028*%
%ADD39C,.123*%
%ADD70R,.028X.024*%
%ADD23R,.028X.032*%
%ADD87R,.054X.044*%
%ADD84R,.015X.046*%
%ADD73R,.024X.028*%
%ADD11C,.125*%
%ADD100C,.315*%
%ADD75R,.062X.046*%
%ADD48R,.044X.054*%
%ADD40R,.046X.062*%
%ADD71R,.197X.116*%
%AMMACRO94*
4,1,8,.037,-.005,
-.005,-.005,
-.005,-.014,
-.037,-.014,
-.037,.014,
-.005,.014,
-.005,.005,
.037,.005,
.037,-.005,
0.0*
%
%ADD94MACRO94*%
%ADD76R,.116X.197*%
%ADD18C,.156*%
%ADD44R,.089X.085*%
%AMMACRO35*
4,1,28,.00748,.00052,
.00984,.00052,
.00984,.00603,
.009782,.006705,
.009607,.007359,
.009321,.007974,
.008933,.008529,
.008455,.009009,
.0079,.009398,
.007286,.009685,
.006632,.009861,
.005957,.00992,
.00591,.00992,
-.00591,.00992,
-.006585,.009869,
-.007242,.009701,
-.007859,.009421,
-.008418,.009039,
-.008903,.008565,
-.009297,.008015,
-.009591,.007404,
-.009773,.006751,
-.00984,.006077,
-.00984,.00603,
-.00984,.00052,
-.00748,.00052,
-.00748,-.00991,
.00748,-.00991,
.00748,.00052,
0.0*
%
%ADD35MACRO35*%
%AMMACRO25*
4,1,28,.00052,-.00748,
.00052,-.00984,
.00603,-.00984,
.006705,-.009782,
.007359,-.009607,
.007974,-.009321,
.008529,-.008933,
.009009,-.008455,
.009398,-.0079,
.009685,-.007286,
.009861,-.006632,
.00992,-.005957,
.00992,-.00591,
.00992,.00591,
.009869,.006585,
.009701,.007242,
.009421,.007859,
.009039,.008418,
.008565,.008903,
.008015,.009297,
.007404,.009591,
.006751,.009773,
.006077,.00984,
.00603,.00984,
.00052,.00984,
.00052,.00748,
-.00991,.00748,
-.00991,-.00748,
.00052,-.00748,
0.0*
%
%ADD25MACRO25*%
%ADD21R,.099X.067*%
%AMMACRO64*
4,1,5,-.01378,-.00098,
-.01378,.00492,
.01378,.00492,
.01378,-.00492,
-.00984,-.00492,
-.01378,-.00098,
0.0*
%
%ADD64MACRO64*%
%AMMACRO34*
4,1,28,.00748,-.00051,
.00984,-.00051,
.00984,-.00602,
.009782,-.006695,
.009607,-.007349,
.009321,-.007964,
.008933,-.008519,
.008455,-.008998,
.0079,-.009388,
.007287,-.009675,
.006632,-.009851,
.005958,-.00991,
.00591,-.00991,
-.00591,-.00991,
-.006585,-.009859,
-.007242,-.009691,
-.007859,-.009411,
-.008418,-.009029,
-.008903,-.008555,
-.009297,-.008005,
-.00959,-.007394,
-.009773,-.006742,
-.00984,-.006068,
-.00984,-.00602,
-.00984,-.00051,
-.00748,-.00051,
-.00748,.00992,
.00748,.00992,
.00748,-.00051,
0.0*
%
%ADD34MACRO34*%
%AMMACRO28*
4,1,5,.01673,-.00492,
.01673,.00492,
-.01673,.00492,
-.01673,-.00098,
-.0128,-.00492,
.01673,-.00492,
0.0*
%
%ADD28MACRO28*%
%AMMACRO24*
4,1,28,-.00051,-.00748,
-.00051,-.00984,
-.00602,-.00984,
-.006695,-.009782,
-.007349,-.009607,
-.007964,-.009321,
-.008519,-.008933,
-.008998,-.008455,
-.009388,-.0079,
-.009675,-.007287,
-.009851,-.006632,
-.00991,-.005958,
-.00991,-.00591,
-.00991,.00591,
-.009859,.006585,
-.009691,.007242,
-.009411,.007859,
-.009029,.008418,
-.008555,.008903,
-.008005,.009297,
-.007394,.00959,
-.006742,.009773,
-.006068,.00984,
-.00602,.00984,
-.00051,.00984,
-.00051,.00748,
.00992,.00748,
.00992,-.00748,
-.00051,-.00748,
0.0*
%
%ADD24MACRO24*%
%AMMACRO59*
4,1,5,-.00098,.01378,
.00492,.01378,
.00492,-.01378,
-.00492,-.01378,
-.00492,.00984,
-.00098,.01378,
0.0*
%
%ADD59MACRO59*%
%AMMACRO63*
4,1,5,-.01378,.00098,
-.01378,-.00492,
.01378,-.00492,
.01378,.00492,
-.00984,.00492,
-.01378,.00098,
0.0*
%
%ADD63MACRO63*%
%AMMACRO58*
4,1,5,.00098,.01378,
-.00492,.01378,
-.00492,-.01378,
.00492,-.01378,
.00492,.00984,
.00098,.01378,
0.0*
%
%ADD58MACRO58*%
%AMMACRO26*
4,1,8,.0246,.01821,
.0246,-.01821,
.01476,-.01821,
.01476,.00837,
-.01477,.00837,
-.01477,-.01821,
-.02461,-.01821,
-.02461,.01821,
.0246,.01821,
0.0*
%
%ADD26MACRO26*%
%ADD101C,.01*%
%ADD102C,.011*%
%ADD103C,.012*%
%ADD104C,.015*%
%ADD105C,.025*%
%ADD106C,.035*%
%ADD107C,.006*%
%ADD108C,.0051*%
%ADD109C,.0068*%
%ADD113C,.03004*%
%ADD119C,.03006*%
%ADD110C,.06004*%
%ADD112C,.10004*%
%ADD121C,.41004*%
%ADD118C,.14004*%
%ADD115C,.21204*%
%ADD111C,.13304*%
%ADD114C,.24304*%
%ADD120C,.40406*%
%ADD117C,.33604*%
%ADD116C,.12806*%
G75*
%LPD*%
G75*
G36*
G01X932200Y576740D02*
X1271654D01*
G02X1289339Y559055I0J-17685D01*
G01Y19685D01*
G02X1271654Y2000I-17685J0D01*
G01X19685D01*
G02X2000Y19685I0J17685D01*
G01Y63268D01*
G02X11811Y73079I9811J0D01*
G01X37796D01*
G03X41184Y74982I-1J3968D01*
G02X41355Y75078I171J-104D01*
G01X42831D01*
G02X43000Y74985I0J-200D01*
G01X43181Y74700D01*
G02X43193Y74507I-169J-107D01*
G02X37796Y71082I-5398J2540D01*
G01X11811D01*
G03X3998Y63270I0J-7813D01*
G01Y19685D01*
G03X19685Y3998I15687J0D01*
G01X1271654D01*
G03X1287341Y19685I0J15687D01*
G01Y559055D01*
G03X1271654Y574742I-15687J0D01*
G01X932200D01*
G02X932000Y574942I0J200D01*
G01Y576540D01*
G02X932200Y576740I200J0D01*
G37*
G36*
G01X41354Y457596D02*
X42832D01*
G02X43001Y457503I0J-200D01*
G01X43181Y457217D01*
G02X43194Y457025I-168J-108D01*
G02X37795Y453600I-5399J2543D01*
G01X11811D01*
G03X3998Y445787I0J-7813D01*
G01Y136102D01*
G03X11811Y128288I7814J0D01*
G01X37796D01*
G02X43193Y124863I-1J-5965D01*
G02X43181Y124670I-181J-86D01*
G01X43000Y124385D01*
G02X42831Y124292I-169J107D01*
G01X41355D01*
G02X41184Y124388I0J200D01*
G03X37796Y126291I-3389J-2065D01*
G01X11811D01*
G02X2000Y136102I0J9811D01*
G01Y445787D01*
G02X11811Y455598I9811J0D01*
G01X37795D01*
G03X41183Y457500I0J3968D01*
G02X41354Y457596I171J-104D01*
G37*
G36*
G01X19685Y576740D02*
X141300D01*
G02X141500Y576540I0J-200D01*
G01Y574942D01*
G02X141300Y574742I-200J0D01*
G01X19685D01*
G03X3998Y559055I0J-15687D01*
G01Y518622D01*
G03X11811Y510808I7814J0D01*
G01X37796D01*
G02X43193Y507384I0J-5966D01*
G02X43181Y507192I-181J-85D01*
G01X43000Y506906D01*
G02X42831Y506814I-168J108D01*
G01X41354D01*
G02X41183Y506909I-1J200D01*
G03X37796Y508811I-3388J-2066D01*
G01X11811D01*
G02X2000Y518622I0J9811D01*
G01Y559055D01*
G02X19685Y576740I17685J0D01*
G37*
G36*
G01X42983Y358000D02*
X52117D01*
G02X52259Y357941I0J-200D01*
G01X55973Y354227D01*
G02X56032Y354085I-141J-142D01*
G01Y354039D01*
X56028Y354019D01*
G03X55998Y353721I1472J-299D01*
G01Y353720D01*
G03X57500Y352218I1502J0D01*
G03X57818Y352252I0J1502D01*
G01X57868Y352263D01*
X57966Y352234D01*
X123076Y287124D01*
Y243424D01*
X133480Y233020D01*
X139880D01*
X140062Y232838D01*
X154202D01*
X154297Y232743D01*
G03X154438Y232685I141J142D01*
G01X159829D01*
G02X159971Y232626I0J-200D01*
G01X160188Y232409D01*
Y217826D01*
X159500Y217138D01*
Y204350D01*
X157000Y201850D01*
X122350D01*
X84500Y239700D01*
Y290040D01*
X43479Y331060D01*
X43451Y331112D01*
X43439Y331173D01*
X43445Y331232D01*
X43457Y331260D01*
X43621Y331655D01*
X43721Y331722D01*
X43782D01*
G03X46782Y334724I-2J3002D01*
G03X43780Y337726I-3002J0D01*
G03X41597Y336784I0J-3000D01*
G01X41545Y336732D01*
X41428Y336708D01*
X41372Y336730D01*
X41026Y336867D01*
G02X40900Y337053I74J186D01*
G01Y337518D01*
G02X40955Y337655I200J-1D01*
G03X40981Y341765I-2175J2069D01*
G01X40956Y341792D01*
X40915Y341894D01*
G02X40900Y341969I185J76D01*
G01Y347479D01*
G02X40915Y347554I200J-1D01*
G01X40956Y347656D01*
X40981Y347683D01*
G03Y351765I-2200J2041D01*
G01X40956Y351792D01*
X40915Y351894D01*
G02X40900Y351969I185J76D01*
G01Y355917D01*
G02X40959Y356059I200J0D01*
G01X42841Y357941D01*
G02X42983Y358000I142J-141D01*
G37*
G36*
G01X150421Y242728D02*
X159359D01*
G02X159500Y242670I0J-200D01*
G01X159881Y242289D01*
G02X159940Y242147I-141J-142D01*
G01Y239813D01*
G02X159881Y239671I-200J0D01*
G01X159399Y239189D01*
G02X159257Y239130I-142J141D01*
G01X150723D01*
G02X150581Y239189I0J200D01*
G01X150199Y239571D01*
G02X150140Y239713I141J142D01*
G01Y242447D01*
G02X150199Y242589I200J0D01*
G01X150280Y242670D01*
G02X150421Y242728I141J-142D01*
G37*
G36*
G01X144699Y244689D02*
X146481Y246471D01*
G02X146623Y246530I142J-141D01*
G01X159657D01*
G02X159799Y246471I0J-200D01*
G01X159881Y246389D01*
G02X159940Y246247I-141J-142D01*
G01Y243913D01*
G02X159881Y243771I-200J0D01*
G01X159870Y243760D01*
X159797Y243730D01*
X149323D01*
G03X149181Y243671I0J-200D01*
G01X148499Y242989D01*
G03X148440Y242847I141J-142D01*
G01Y239613D01*
G02X148381Y239471I-200J0D01*
G01X148199Y239289D01*
G02X148057Y239230I-142J141D01*
G01X145223D01*
G02X145081Y239289I0J200D01*
G01X144699Y239671D01*
G02X144640Y239813I141J142D01*
G01Y244547D01*
G02X144699Y244689I200J0D01*
G37*
G36*
G01X141373Y237070D02*
X153774D01*
G02X153916Y237011I0J-200D01*
G01X155598Y235329D01*
G03X155740Y235270I142J141D01*
G01X159807D01*
G02X159949Y235211I0J-200D01*
G01X160131Y235029D01*
G02X160190Y234887I-141J-142D01*
G01Y233770D01*
G02X159990Y233570I-200J0D01*
G01X155330D01*
X155078Y233822D01*
X141092D01*
X140690Y234224D01*
Y236387D01*
G02X140749Y236529I200J0D01*
G01X141231Y237011D01*
G02X141373Y237070I142J-141D01*
G37*
G36*
G01X221681Y453814D02*
X758603D01*
G02X758745Y453755I0J-200D01*
G01X767641Y444859D01*
G02X767700Y444717I-141J-142D01*
G01Y323283D01*
G02X767641Y323141I-200J0D01*
G01X766059Y321559D01*
G02X765917Y321500I-142J141D01*
G01X747235D01*
G02X747063Y321598I0J200D01*
G01X746861Y321940D01*
X746859Y322046D01*
X746885Y322092D01*
G03X747502Y324500I-4385J2407D01*
G03X747118Y326423I-5002J1D01*
G02Y326577I184J77D01*
G03X747502Y328498I-4618J1922D01*
G01Y328500D01*
G03X746586Y331385I-5001J0D01*
G02Y331615I164J115D01*
G03X747502Y334500I-4085J2885D01*
G03X745943Y338129I-5003J0D01*
G02X745924Y338398I138J145D01*
G03X747002Y341500I-3924J3102D01*
G01Y341501D01*
G03X746237Y344159I-5002J-1D01*
G02X746256Y344397I169J106D01*
G03X747502Y347700I-3755J3303D01*
G03X746746Y350344I-5002J0D01*
G02Y350556I170J106D01*
G03X747502Y353200I-4246J2644D01*
G03X737498I-5002J0D01*
G03X738254Y350556I5002J0D01*
G02Y350344I-170J-106D01*
G03X737498Y347700I4246J-2644D01*
G01Y347699D01*
G03X738263Y345041I5002J1D01*
G02X738244Y344803I-169J-106D01*
G03X736998Y341500I3755J-3303D01*
G03X738557Y337871I5003J0D01*
G02X738576Y337602I-138J-145D01*
G03X737498Y334500I3924J-3102D01*
G03X738414Y331615I5001J0D01*
G02Y331385I-164J-115D01*
G03X737498Y328500I4085J-2885D01*
G01Y328498D01*
G03X737882Y326577I5002J1D01*
G02Y326423I-184J-77D01*
G03X737498Y324500I4618J-1922D01*
G03X738115Y322092I5002J-1D01*
G01X738141Y322046D01*
X738139Y321940D01*
X737937Y321598D01*
G02X737765Y321500I-172J102D01*
G01X199429D01*
G03X199287Y321441I0J-200D01*
G01X192149Y314303D01*
G03X192090Y314161I141J-142D01*
G01Y294884D01*
G03X192149Y294742I200J0D01*
G01X200734Y286157D01*
G02X200793Y286015I-141J-142D01*
G01Y279755D01*
G02X200630Y279559I-200J1D01*
G01X200172Y279473D01*
X200046Y279544D01*
X200020Y279611D01*
G03X193819Y283856I-6201J-2407D01*
G03Y270552I0J-6652D01*
G03X196239Y271008I0J6652D01*
G01X196305Y271034D01*
X196440Y270991D01*
X196734Y270540D01*
X196721Y270415D01*
G03X196720Y270395I199J-20D01*
G01Y264935D01*
G03X196779Y264793I200J0D01*
G01X203341Y258231D01*
G02X203400Y258089I-141J-142D01*
G01Y229900D01*
X202596Y229096D01*
X191396D01*
X189540Y227240D01*
Y222700D01*
X185932Y219092D01*
X185904Y219063D01*
X185830Y219033D01*
X180837D01*
G02X180695Y219092I0J200D01*
G01X180559Y219228D01*
X180530Y219256D01*
X180500Y219330D01*
Y253300D01*
X176800Y257000D01*
X157772D01*
X155272Y254500D01*
X129500D01*
X128924Y255076D01*
Y271424D01*
X137424Y279924D01*
Y369640D01*
X221539Y453755D01*
G02X221681Y453814I142J-141D01*
G37*
G36*
G01X153583Y570869D02*
X873098D01*
G02X873240Y570810I0J-200D01*
G01X876580Y567470D01*
G02X876628Y567265I-141J-141D01*
G01X876497Y566871D01*
X876410Y566799D01*
X876353Y566791D01*
G03X869258Y558620I1158J-8171D01*
G03X876817Y550397I8252J0D01*
G02X877000Y550198I-17J-199D01*
G01Y463483D01*
G02X876941Y463341I-200J0D01*
G01X874916Y461316D01*
X149971D01*
G02X149829Y461375I0J200D01*
G01X147822Y463381D01*
G02X147763Y463523I141J142D01*
G01Y558080D01*
X147793Y558154D01*
X147822Y558182D01*
Y565108D01*
G02X147881Y565250I200J0D01*
G01X153441Y570810D01*
G02X153583Y570869I142J-141D01*
G37*
G36*
G01X760300Y307700D02*
X776717D01*
G02X776859Y307641I0J-200D01*
G01X779941Y304559D01*
G02X780000Y304417I-141J-142D01*
G01Y263819D01*
X780690Y263129D01*
X783491D01*
X783800Y262820D01*
Y256473D01*
G03X783859Y256331I200J0D01*
G01X786026Y254164D01*
G03X786168Y254105I142J141D01*
G01X835417D01*
G02X835559Y254046I0J-200D01*
G01X839464Y250141D01*
Y166460D01*
X836503Y163500D01*
X804259D01*
G03X804117Y163441I0J-200D01*
G01X798235Y157559D01*
G03X798176Y157417I141J-142D01*
G01Y81730D01*
X792619Y76173D01*
X646754D01*
X643500Y72919D01*
X642897Y72316D01*
Y38477D01*
X643313Y38061D01*
Y9613D01*
X641700Y8000D01*
X635403D01*
G03X633761I-821J-4997D01*
G01X614840D01*
G03X614583Y8008I-284J-4995D01*
G01X614581D01*
G03X614324Y8000I27J-5003D01*
G01X594840D01*
G03X594583Y8008I-284J-4995D01*
G01X594581D01*
G03X594324Y8000I27J-5003D01*
G01X574840D01*
G03X574583Y8008I-284J-4995D01*
G01X574581D01*
G03X574324Y8000I27J-5003D01*
G01X554840D01*
G03X554583Y8008I-284J-4995D01*
G01X554581D01*
G03X554324Y8000I27J-5003D01*
G01X534840D01*
G03X534583Y8008I-284J-4995D01*
G01X534581D01*
G03X534324Y8000I27J-5003D01*
G01X514840D01*
G03X514583Y8008I-284J-4995D01*
G01X514581D01*
G03X514324Y8000I27J-5003D01*
G01X494840D01*
G03X494583Y8008I-284J-4995D01*
G01X494581D01*
G03X494324Y8000I27J-5003D01*
G01X474840D01*
G03X474583Y8008I-284J-4995D01*
G01X474581D01*
G03X474324Y8000I27J-5003D01*
G01X454840D01*
G03X454583Y8008I-284J-4995D01*
G01X454581D01*
G03X454324Y8000I27J-5003D01*
G01X434840D01*
G03X434583Y8008I-284J-4995D01*
G01X434581D01*
G03X434324Y8000I27J-5003D01*
G01X414840D01*
G03X414583Y8008I-284J-4995D01*
G01X414581D01*
G03X414324Y8000I27J-5003D01*
G01X394840D01*
G03X394583Y8008I-284J-4995D01*
G01X394581D01*
G03X394324Y8000I27J-5003D01*
G01X374840D01*
G03X374583Y8008I-284J-4995D01*
G01X374581D01*
G03X374324Y8000I27J-5003D01*
G01X354840D01*
G03X354583Y8008I-284J-4995D01*
G01X354581D01*
G03X354324Y8000I27J-5003D01*
G01X334840D01*
G03X334583Y8008I-284J-4995D01*
G01X334581D01*
G03X334324Y8000I27J-5003D01*
G01X314840D01*
G03X314583Y8008I-284J-4995D01*
G01X314581D01*
G03X314324Y8000I27J-5003D01*
G01X294840D01*
G03X294583Y8008I-284J-4995D01*
G01X294581D01*
G03X294324Y8000I27J-5003D01*
G01X274840D01*
G03X274583Y8008I-284J-4995D01*
G01X274581D01*
G03X274324Y8000I27J-5003D01*
G01X254840D01*
G03X254583Y8008I-284J-4995D01*
G01X254581D01*
G03X254324Y8000I27J-5003D01*
G01X234840D01*
G03X234583Y8008I-284J-4995D01*
G01X234581D01*
G03X234324Y8000I27J-5003D01*
G01X214840D01*
G03X214583Y8008I-284J-4995D01*
G01X214581D01*
G03X214324Y8000I27J-5003D01*
G01X195284D01*
X195242Y8008D01*
X195211Y8014D01*
X195159Y8041D01*
X189908Y13292D01*
G02X189849Y13434I141J142D01*
G01Y114951D01*
X161600Y143200D01*
Y232929D01*
X161670Y232999D01*
X166428D01*
X166600Y232827D01*
Y217000D01*
X166617D01*
X173157Y210460D01*
G03X173299Y210401I142J141D01*
G01X189501D01*
X191641Y212541D01*
G03X191700Y212683I-141J142D01*
G01Y217017D01*
G02X191759Y217159I200J0D01*
G01X192845Y218245D01*
G02X192987Y218304I142J-141D01*
G01X203921D01*
G03X204063Y218363I0J200D01*
G01X207700Y222000D01*
Y259388D01*
X208953Y260641D01*
X209009Y260669D01*
X209041Y260674D01*
G03X211890Y261818I-968J6531D01*
G01X211914Y261835D01*
X211968Y261854D01*
X212000Y261855D01*
G02X212094Y261836I9J-200D01*
G01X212118Y261824D01*
X212132Y261814D01*
G03X214048Y260881I3811J5392D01*
G03X215945Y260602I1899J6323D01*
G01X215946D01*
G03X219761Y261816I0J6602D01*
G01X219767Y261821D01*
X219777Y261827D01*
G02X219872Y261855I102J-172D01*
G01X219923Y261857D01*
X219968Y261835D01*
X219987Y261827D01*
X220004Y261815D01*
G03X224567Y260644I3815J5390D01*
G03X227635Y261816I-748J6560D01*
G01X227641Y261821D01*
X227651Y261827D01*
G02X227746Y261855I102J-172D01*
G01X227797Y261857D01*
X227842Y261835D01*
X227861Y261827D01*
X227878Y261815D01*
G03X232441Y260644I3815J5390D01*
G03X235509Y261816I-748J6560D01*
G01X235515Y261821D01*
X235525Y261827D01*
G02X235620Y261855I102J-172D01*
G01X235671Y261857D01*
X235716Y261835D01*
X235735Y261827D01*
X235752Y261815D01*
G03X240152Y260628I3814J5390D01*
G03X243386Y261819I-585J6576D01*
G02X243487Y261855I115J-164D01*
G01X243541Y261859D01*
X243617Y261822D01*
X243630Y261813D01*
G03X247441Y260602I3811J5391D01*
G03X254043Y267204I0J6602D01*
G03X253453Y269932I-6602J0D01*
G01X253452Y269933D01*
X253437Y269968D01*
G02X253425Y270003I183J82D01*
G01X253420Y270028D01*
G02X253446Y270181I195J46D01*
G01X253625Y270460D01*
G02X253793Y270552I168J-108D01*
G01X253819D01*
G03X247167Y277204I0J6652D01*
G01Y277202D01*
G03X247798Y274374I6653J0D01*
G01X247807Y274354D01*
X247813Y274331D01*
G02X247785Y274179I-195J-43D01*
G01X247615Y273915D01*
G03X247608Y273903I169J-107D01*
G01X247584Y273861D01*
X247491Y273806D01*
X247432D01*
G03X246797Y273774I14J-6602D01*
G01X246751Y273770D01*
X246668Y273800D01*
X246027Y274441D01*
G02X245968Y274583I141J142D01*
G01Y306885D01*
G02X246027Y307027I200J0D01*
G01X246641Y307641D01*
G02X246783Y307700I142J-141D01*
G01X355761D01*
G02X355901Y307643I0J-200D01*
G01X355921Y307623D01*
X356112Y307378D01*
G02X356154Y307250I-158J-123D01*
G01Y307248D01*
X356153Y307219D01*
X356151Y307209D01*
X356150Y307206D01*
X356147Y307194D01*
G03X355996Y305975I4853J-1220D01*
G01Y305904D01*
X356001Y305783D01*
G03X359752Y301130I4999J192D01*
G01X359784Y301122D01*
X359838Y301087D01*
X359861Y301058D01*
X359866Y301052D01*
G03X359897Y301023I151J130D01*
G01X359910Y301014D01*
G03X360021Y300980I112J166D01*
G01X360738D01*
X360743Y300979D01*
G03X361000Y300973I245J4996D01*
G03X361257Y300979I12J5002D01*
G01X361262Y300980D01*
X365289D01*
X365294Y300979D01*
G03X365551Y300973I245J4996D01*
G03X365808Y300979I12J5002D01*
G01X365813Y300980D01*
X372400D01*
G02X372462Y300970I0J-200D01*
G01X372549Y300942D01*
X372583Y300918D01*
X372584D01*
G03X375475Y299998I2891J4082D01*
G01X375499D01*
G03X378373Y300923I-24J5002D01*
G01X378374Y300924D01*
X378401Y300942D01*
X378518Y300980D01*
X380900D01*
G02X380962Y300970I0J-200D01*
G01X381049Y300942D01*
X381083Y300918D01*
X381084D01*
G03X383975Y299998I2891J4082D01*
G01X383999D01*
G03X386873Y300923I-24J5002D01*
G01X386874Y300924D01*
X386901Y300942D01*
X387018Y300980D01*
X389925D01*
G02X389987Y300970I0J-200D01*
G01X390074Y300942D01*
X390108Y300918D01*
X390109D01*
G03X393000Y299998I2891J4082D01*
G01X393024D01*
G03X395925Y300942I-24J5002D01*
G02X396042Y300980I117J-162D01*
G01X396788D01*
G03X396826Y300978I282J4994D01*
G01X396827D01*
G03X397047Y300971I269J4996D01*
G01X397048D01*
G03X402051Y305975I-1J5004D01*
G03X401897Y307203I-5004J-4D01*
G01X401885Y307249D01*
X401904Y307338D01*
X402126Y307623D01*
G02X402283Y307700I158J-123D01*
G01X517793D01*
G02X517933Y307643I0J-200D01*
G01X517953Y307623D01*
X518144Y307380D01*
G02X518186Y307237I-157J-124D01*
G01X518184Y307218D01*
X518180Y307203D01*
G03X518028Y305986I4852J-1224D01*
G01X518029Y305985D01*
X518031Y305903D01*
G03X523032Y300973I5001J72D01*
G03X523100I34J5002D01*
G01X531303D01*
G02X531387Y300955I1J-200D01*
G03X533460Y300498I2089J4545D01*
G01X533476D01*
G03X535555Y300951I-1J5002D01*
G01X535564Y300955D01*
X535579Y300961D01*
G02X535649Y300973I68J-188D01*
G01X540303D01*
G02X540387Y300955I1J-200D01*
G03X542460Y300498I2089J4545D01*
G01X542476D01*
G03X544555Y300951I-1J5002D01*
G01X544564Y300955D01*
X544579Y300961D01*
G02X544649Y300973I68J-188D01*
G01X549294D01*
G02X549318Y300972I4J-200D01*
G01X549361Y300966D01*
X549390Y300953D01*
G03X551474Y300498I2084J4547D01*
G01X551475D01*
G03X553563Y300955I-1J5002D01*
G01X553603Y300973D01*
X554730D01*
Y300977D01*
G03X559530Y305975I-202J4998D01*
G01Y305979D01*
G03X559381Y307189I-5002J-2D01*
G01X559377Y307203D01*
X559374Y307236D01*
G02X559415Y307377I199J19D01*
G01X559607Y307623D01*
G02X559764Y307700I158J-123D01*
G01X670173D01*
X671073Y306800D01*
Y299551D01*
G03X675971Y294599I5002J49D01*
G01X675975D01*
G03X676075Y294598I100J5001D01*
G03X676175Y294599I0J5002D01*
G01X689393D01*
X689502Y294511D01*
X689517Y294441D01*
G03X699295I4889J1059D01*
G01X699316Y294539D01*
X699351Y294568D01*
X699390Y294649D01*
Y295076D01*
X699391Y295084D01*
G03X699408Y295500I-4985J412D01*
G03X699391Y295916I-5002J4D01*
G01X699390Y295924D01*
Y299600D01*
X700297Y300507D01*
G03X700591Y300533I-293J4993D01*
G01X708362D01*
G03X708956Y300498I591J4967D01*
G03X711104Y300983I-1J5002D01*
G01X711125Y300993D01*
G03X711158Y301009I-2166J4509D01*
G02X711275Y301027I88J-180D01*
G03X711470Y301002I733J4948D01*
G01X711471D01*
X711482Y301001D01*
G03X712009Y300973I529J4974D01*
G03X717011Y305975I0J5002D01*
G03X716858Y307202I-5002J-1D01*
G01X716847Y307247D01*
X716866Y307337D01*
X716886Y307362D01*
G02X716896Y307377I171J-103D01*
G01X717088Y307623D01*
G02X717245Y307700I158J-123D01*
G01X740100D01*
X741800Y306000D01*
X758600D01*
X760300Y307700D01*
G37*
G36*
G01X165000Y248900D02*
X170300D01*
X171100Y248100D01*
Y244600D01*
X171005Y244505D01*
X164995D01*
X164800Y244700D01*
Y248700D01*
X165000Y248900D01*
G37*
G36*
G01X168386Y243155D02*
X171332D01*
X171544Y242943D01*
Y234143D01*
X170994Y233593D01*
X168274D01*
X168024Y233843D01*
Y242793D01*
X168386Y243155D01*
G37*
G36*
G01X199709Y286157D02*
X200734D01*
X201873Y285018D01*
Y279079D01*
G02X201932Y278937I-141J-142D01*
G01Y272991D01*
G02X201873Y272849I-200J0D01*
G01X199521Y270497D01*
G02X199379Y270438I-142J141D01*
G01X198322D01*
G03X198180Y270379I0J-200D01*
G01X195928Y268127D01*
G02X195711Y268084I-141J142D01*
G01X195654Y268107D01*
X195587Y268208D01*
Y270791D01*
G03X197750Y271838I-1769J6412D01*
G01X197751D01*
G03X199610Y273930I-3932J5366D01*
G01X199623Y273953D01*
Y273954D01*
X199715Y274046D01*
G03X199774Y274188I-141J142D01*
G01Y274239D01*
X199795Y274280D01*
G03X200472Y277204I-5976J2924D01*
G01X200471Y277206D01*
G03X200281Y278783I-6652J-2D01*
G03X199176Y281148I-6462J-1579D01*
G01Y285624D01*
X199709Y286157D01*
G37*
G36*
G01X245968Y278968D02*
X246000Y279000D01*
X247194Y277806D01*
G03X247167Y277211I6625J-599D01*
G01Y277204D01*
G03X253819Y270552I6652J0D01*
G03X258511Y272489I0J6651D01*
G01X263000Y268000D01*
Y262000D01*
X261000Y260000D01*
X253100D01*
X252200Y260900D01*
Y266549D01*
X251545Y267204D01*
G03X247441Y271308I-4104J0D01*
G03X247014Y271286I-3J-4104D01*
G01X245968Y272332D01*
Y278968D01*
G37*
G36*
G01X694500Y47900D02*
X700000D01*
X700100Y47800D01*
Y46800D01*
X700000Y46700D01*
X694900D01*
X693700D01*
X690700Y43700D01*
X688550Y41550D01*
X688500D01*
X687450Y40500D01*
X677500D01*
X675400Y38400D01*
X652100D01*
X648950Y41550D01*
X646050D01*
X645400Y42200D01*
Y47800D01*
X646100Y48500D01*
X646300Y48700D01*
X669500D01*
X693700D01*
X694500Y47900D01*
G37*
G36*
G01X699450Y58650D02*
Y54850D01*
Y51350D01*
X698900Y50800D01*
X694500D01*
X694400Y50700D01*
X693750Y50050D01*
X648950D01*
X648000Y51000D01*
Y69500D01*
X650535Y72035D01*
X697413D01*
X699450Y69998D01*
Y67050D01*
Y62350D01*
Y58650D01*
G37*
G36*
G01X700535Y43095D02*
X701435D01*
X701535Y42995D01*
Y38895D01*
X702635Y37795D01*
Y35895D01*
Y35612D01*
X700762Y33739D01*
X698361D01*
X697100Y35000D01*
X696635Y35465D01*
Y35695D01*
Y37395D01*
X697035Y37795D01*
X699735D01*
X700435Y38495D01*
Y42995D01*
X700535Y43095D01*
G37*
G36*
G01X722500Y57500D02*
Y44500D01*
X722000Y44000D01*
X719000D01*
X713900D01*
X713132Y44768D01*
Y46868D01*
X711500Y48500D01*
X707000D01*
X706800Y48700D01*
X694900D01*
X694800Y48800D01*
Y49800D01*
X694900Y49900D01*
X705650D01*
X707650Y51900D01*
Y57150D01*
X708500Y58000D01*
X709500Y59000D01*
Y61700D01*
X710700Y62900D01*
X720600D01*
X722500Y61000D01*
Y57500D01*
G37*
G36*
G01X701600Y51500D02*
X700500D01*
X700400Y51600D01*
Y54900D01*
Y55500D01*
Y56100D01*
X700700Y56400D01*
Y58500D01*
Y58800D01*
X700900Y59000D01*
X702700D01*
X702900Y58800D01*
Y58500D01*
Y55400D01*
X701700Y54200D01*
Y51600D01*
X701600Y51500D01*
G37*
G36*
G01X754000Y70202D02*
Y26000D01*
X753000Y25000D01*
X731194D01*
X730488Y25706D01*
X730487Y25707D01*
X729126Y27068D01*
G02X729067Y27210I141J142D01*
G01Y70227D01*
X730718Y71878D01*
X752324D01*
X754000Y70202D01*
G37*
G36*
G01X769637Y71863D02*
X770000Y71500D01*
Y26000D01*
X769000Y25000D01*
X755500D01*
X754943Y25557D01*
Y26075D01*
G02X754884Y26217I141J142D01*
G01Y71283D01*
G02X754943Y71425I200J0D01*
G01X755381Y71863D01*
X769637D01*
G37*
G36*
G01X1063000Y566262D02*
X1081057D01*
X1082319Y565000D01*
Y523361D01*
X1082000Y523042D01*
X1062942D01*
X1052900Y513000D01*
Y502210D01*
X1057610Y497500D01*
X1081500D01*
X1082420Y496580D01*
Y475962D01*
X1082000Y475542D01*
X1057610D01*
X1052900Y470832D01*
Y454710D01*
X1057610Y450000D01*
X1081500D01*
X1082845Y448655D01*
Y428887D01*
X1082000Y428042D01*
X1057610D01*
X1052900Y423332D01*
Y407210D01*
X1057610Y402500D01*
X1081500D01*
X1082685Y401315D01*
Y381227D01*
X1082000Y380542D01*
X1057610D01*
X1052900Y375832D01*
Y359710D01*
X1057610Y355000D01*
X1081500D01*
X1082739Y353761D01*
Y333781D01*
X1082000Y333042D01*
X1057610D01*
X1052900Y328332D01*
Y312210D01*
X1057610Y307500D01*
X1081500D01*
X1082792Y306208D01*
Y286334D01*
X1082000Y285542D01*
X1057610D01*
X1052900Y280832D01*
Y264710D01*
X1057610Y260000D01*
X1081500D01*
X1082685Y258815D01*
Y241500D01*
X1018741D01*
X1002241Y258000D01*
X966800D01*
X962000Y262800D01*
Y375500D01*
X958200Y379300D01*
X780800D01*
X776494Y383606D01*
Y450506D01*
X779500Y453512D01*
X880212D01*
X883000Y456300D01*
Y529000D01*
X885500Y531500D01*
X912500D01*
X931500Y512500D01*
X1043500D01*
X1060500Y529500D01*
Y563762D01*
X1063000Y566262D01*
G37*
G36*
G01X850363Y154750D02*
X937497D01*
G02X937639Y154691I0J-200D01*
G01X939391Y152939D01*
G02X939450Y152797I-141J-142D01*
G01Y115883D01*
G02X939391Y115741I-200J0D01*
G01X937409Y113759D01*
G02X937267Y113700I-142J141D01*
G01X850073D01*
G02X849931Y113759I0J200D01*
G01X848299Y115391D01*
G02X848240Y115533I141J142D01*
G01Y152627D01*
G02X848299Y152769I200J0D01*
G01X850221Y154691D01*
G02X850363Y154750I142J-141D01*
G37*
G36*
G01X845740Y373000D02*
X954850D01*
X955100Y372750D01*
Y364560D01*
X954740Y364200D01*
X845560D01*
X845020Y364740D01*
Y372280D01*
X845740Y373000D01*
G37*
G36*
G01X1024882Y225600D02*
X1109317D01*
G02X1109459Y225541I0J-200D01*
G01X1109641Y225359D01*
G02X1109700Y225217I-141J-142D01*
G01Y214883D01*
G03X1109759Y214741I200J0D01*
G01X1111441Y213059D01*
G03X1111583Y213000I142J141D01*
G01X1143117D01*
G02X1143259Y212941I0J-200D01*
G01X1143741Y212459D01*
G02X1143800Y212317I-141J-142D01*
G01Y203300D01*
G02X1143600Y203100I-200J0D01*
G01X1137483D01*
G03X1137341Y203041I0J-200D01*
G01X1134184Y199884D01*
G03X1134125Y199742I141J-142D01*
G01Y198051D01*
X1134110Y197999D01*
X1134096Y197975D01*
G03X1134066Y197870I170J-105D01*
G01Y194698D01*
G02X1134007Y194556I-200J0D01*
G01X1133921Y194470D01*
X1133893Y194441D01*
X1133819Y194411D01*
X1132312D01*
G02X1132170Y194470I0J200D01*
G01X1131938Y194702D01*
X1131909Y194730D01*
X1131879Y194804D01*
Y198583D01*
G03X1131820Y198725I-200J0D01*
G01X1131048Y199497D01*
G03X1130906Y199556I-142J-141D01*
G01X1124017D01*
G03X1123875Y199497I0J-200D01*
G01X1123148Y198770D01*
G03X1123089Y198628I141J-142D01*
G01Y194832D01*
G02X1123030Y194690I-200J0D01*
G01X1122855Y194515D01*
X1122827Y194486D01*
X1122753Y194456D01*
X1105172D01*
G02X1105030Y194515I0J200D01*
G01X1104854Y194691D01*
X1104825Y194719D01*
X1104795Y194793D01*
Y208800D01*
X1103484Y210111D01*
X1081616D01*
X1078175Y206670D01*
Y192645D01*
X1081780Y189040D01*
X1085523D01*
G03X1085665Y188981I142J141D01*
G01X1097174D01*
G02X1097316Y188922I0J-200D01*
G01X1097416Y188822D01*
G02X1097475Y188680I-141J-142D01*
G01Y182853D01*
G02X1097416Y182711I-200J0D01*
G01X1097359Y182654D01*
X1097331Y182625D01*
X1097257Y182595D01*
X1092716D01*
G03X1092574Y182536I0J-200D01*
G01X1091643Y181605D01*
G03X1091584Y181463I141J-142D01*
G01Y177027D01*
G03X1091643Y176885I200J0D01*
G01X1093886Y174642D01*
G02X1093945Y174500I-141J-142D01*
G01Y170960D01*
G03X1094004Y170818I200J0D01*
G01X1094499Y170323D01*
G03X1094641Y170264I142J141D01*
G01X1096826D01*
G02X1096968Y170205I0J-200D01*
G01X1097152Y170021D01*
G02X1097211Y169879I-141J-142D01*
G01Y165094D01*
G02X1097152Y164952I-200J0D01*
G01X1095059Y162859D01*
X1095031Y162830D01*
X1094957Y162800D01*
X1084383D01*
G02X1084241Y162859I0J200D01*
G01X1082634Y164466D01*
X1082605Y164494D01*
X1082575Y164568D01*
Y178436D01*
G03X1082516Y178578I-200J0D01*
G01X1073153Y187941D01*
G03X1073011Y188000I-142J-141D01*
G01X1066083D01*
G02X1065941Y188059I0J200D01*
G01X1065559Y188441D01*
X1065530Y188469D01*
X1065500Y188543D01*
Y192417D01*
G03X1065441Y192559I-200J0D01*
G01X1064559Y193441D01*
G03X1064417Y193500I-142J-141D01*
G01X1047583D01*
G03X1047441Y193441I0J-200D01*
G01X1046053Y192053D01*
G03X1045994Y191911I141J-142D01*
G01Y173741D01*
X1046294Y173441D01*
X1049038D01*
G02X1049238Y173241I0J-200D01*
G01Y152285D01*
G02X1049038Y152085I-200J0D01*
G01X1042531D01*
G03X1042389Y152026I0J-200D01*
G01X1042150Y151787D01*
G03X1042091Y151645I141J-142D01*
G01Y150772D01*
X1042089Y150770D01*
Y130586D01*
G02X1042030Y130444I-200J0D01*
G01X1040804Y129218D01*
G03X1040745Y129076I141J-142D01*
G01Y125157D01*
G03X1040804Y125015I200J0D01*
G01X1042460Y123359D01*
G03X1042602Y123300I142J141D01*
G01X1051517D01*
G03X1051659Y123359I0J200D01*
G01X1052941Y124641D01*
G03X1053000Y124783I-141J142D01*
G01Y132317D01*
G02X1053059Y132459I200J0D01*
G01X1056062Y135462D01*
G03X1056121Y135604I-141J142D01*
G01Y139063D01*
G02X1056180Y139205I200J0D01*
G01X1056931Y139956D01*
G02X1057073Y140015I142J-141D01*
G01X1062941D01*
G02X1063083Y139956I0J-200D01*
G01X1063741Y139298D01*
G02X1063800Y139156I-141J-142D01*
G01Y123583D01*
G03X1063859Y123441I200J0D01*
G01X1066241Y121059D01*
G03X1066383Y121000I142J141D01*
G01X1094795D01*
X1101941Y128146D01*
Y132041D01*
G03X1102000Y132183I-141J142D01*
G01Y139717D01*
G02X1102059Y139859I200J0D01*
G01X1102241Y140041D01*
G02X1102383Y140100I142J-141D01*
G01X1105217D01*
G02X1105359Y140041I0J-200D01*
G01X1105541Y139859D01*
G02X1105600Y139717I-141J-142D01*
G01Y133783D01*
G03X1105659Y133641I200J0D01*
G01X1106741Y132559D01*
G03X1106883Y132500I142J141D01*
G01X1110217D01*
G03X1110359Y132559I0J200D01*
G01X1114841Y137041D01*
G02X1114983Y137100I142J-141D01*
G01X1115717D01*
G03X1115859Y137159I0J200D01*
G01X1118641Y139941D01*
G02X1118783Y140000I142J-141D01*
G01X1123417D01*
G02X1123559Y139941I0J-200D01*
G01X1123941Y139559D01*
G02X1124000Y139417I-141J-142D01*
G01Y137583D01*
G02X1123941Y137441I-200J0D01*
G01X1122559Y136059D01*
X1122531Y136030D01*
X1122457Y136000D01*
X1118949D01*
G03X1118807Y135941I0J-200D01*
G01X1110359Y127493D01*
G03X1110300Y127351I141J-142D01*
G01Y117283D01*
G03X1110359Y117141I200J0D01*
G01X1115082Y112418D01*
G03X1115224Y112359I142J141D01*
G01X1117780D01*
X1117832Y112344D01*
X1117856Y112330D01*
G03X1117961Y112300I105J170D01*
G01X1138417D01*
G03X1138559Y112359I0J200D01*
G01X1138622Y112422D01*
Y112431D01*
X1143801Y117610D01*
G03X1143860Y117752I-141J142D01*
G01Y135757D01*
G03X1143801Y135899I-200J0D01*
G01X1142359Y137341D01*
G03X1142217Y137400I-142J-141D01*
G01X1132513D01*
G02X1132371Y137459I0J200D01*
G01X1132249Y137581D01*
X1132220Y137609D01*
X1132190Y137683D01*
Y149197D01*
G03X1132131Y149339I-200J0D01*
G01X1130459Y151011D01*
X1130430Y151039D01*
X1130400Y151113D01*
Y155133D01*
G03X1130341Y155275I-200J0D01*
G01X1130069Y155547D01*
G03X1129927Y155606I-142J-141D01*
G01X1119214D01*
G02X1119072Y155665I0J200D01*
G01X1119070Y155667D01*
G02X1119011Y155809I141J142D01*
G01Y177576D01*
G02X1119211Y177776I200J0D01*
G01X1129940D01*
G02X1130082Y177717I0J-200D01*
G01X1130118Y177681D01*
G02X1130177Y177539I-141J-142D01*
G01Y157276D01*
G03X1130236Y157134I200J0D01*
G01X1131661Y155709D01*
G02X1131720Y155567I-141J-142D01*
G01Y152063D01*
G03X1131779Y151921I200J0D01*
G01X1135011Y148689D01*
X1135293Y148407D01*
X1146585D01*
Y126947D01*
X1146589Y126943D01*
X1147247Y126285D01*
Y115247D01*
X1138059Y106059D01*
X1138031Y106030D01*
X1137957Y106000D01*
X1053795D01*
G02X1053653Y106059I0J200D01*
G01X1041071Y118641D01*
G03X1040929Y118700I-142J-141D01*
G01X1030083D01*
G02X1029941Y118759I0J200D01*
G01X1027859Y120841D01*
G03X1027717Y120900I-142J-141D01*
G01X1015483D01*
G02X1015341Y120959I0J200D01*
G01X1007559Y128741D01*
X1007530Y128769D01*
X1007500Y128843D01*
Y173917D01*
G03X1007441Y174059I-200J0D01*
G01X999059Y182441D01*
X999030Y182469D01*
X999000Y182543D01*
Y199718D01*
G02X999059Y199860I200J0D01*
G01X1024740Y225541D01*
G02X1024882Y225600I142J-141D01*
G37*
G36*
G01X1065500Y129900D02*
X1073900D01*
X1074400Y129400D01*
Y123700D01*
Y122900D01*
X1073600Y122100D01*
X1072800D01*
X1066800D01*
X1065300Y123600D01*
Y129700D01*
X1065500Y129900D01*
G37*
G36*
G01X1043307Y125007D02*
X1050907D01*
X1051770Y125870D01*
Y127186D01*
X1049066Y129890D01*
Y132152D01*
X1048906Y132312D01*
X1043231D01*
X1043043Y132124D01*
Y125271D01*
X1043307Y125007D01*
G37*
G36*
G01X1075185Y153203D02*
X1079105D01*
X1079280Y153028D01*
Y140200D01*
X1075807Y136727D01*
X1065428D01*
X1065267Y136888D01*
X1065293D01*
Y141332D01*
X1065435Y141474D01*
X1071614D01*
X1074995Y144855D01*
Y153013D01*
X1075185Y153203D01*
G37*
G36*
G01X1042890Y150868D02*
Y142377D01*
X1043050Y142217D01*
X1044902D01*
X1045106Y142421D01*
Y144069D01*
Y146445D01*
X1044013Y147538D01*
Y150885D01*
X1043977Y150921D01*
X1042943D01*
X1042890Y150868D01*
G37*
G36*
G01X1063100Y273200D02*
X1082200D01*
X1082400Y273000D01*
Y267900D01*
X1082200Y267700D01*
X1063100D01*
X1062900Y267900D01*
Y273000D01*
X1063100Y273200D01*
G37*
G36*
G01Y320700D02*
X1082200D01*
X1082400Y320500D01*
Y315400D01*
X1082200Y315200D01*
X1063100D01*
X1062900Y315400D01*
Y320500D01*
X1063100Y320700D01*
G37*
G36*
G01X1063600Y368200D02*
X1082200D01*
X1082400Y368000D01*
Y362900D01*
X1082200Y362700D01*
X1064000D01*
X1062900Y363800D01*
Y367500D01*
X1063600Y368200D01*
G37*
G36*
G01X1063100Y415700D02*
X1082200D01*
X1082400Y415500D01*
Y410400D01*
X1082200Y410200D01*
X1063100D01*
X1062900Y410400D01*
Y415500D01*
X1063100Y415700D01*
G37*
G36*
G01Y463200D02*
X1082200D01*
X1082400Y463000D01*
Y457900D01*
X1082200Y457700D01*
X1063100D01*
X1062900Y457900D01*
Y463000D01*
X1063100Y463200D01*
G37*
G36*
G01Y510700D02*
X1082200D01*
X1082400Y510500D01*
Y505400D01*
X1082200Y505200D01*
X1063100D01*
X1062900Y505400D01*
Y510500D01*
X1063100Y510700D01*
G37*
G36*
G01X1281129Y19098D02*
X1269069Y7038D01*
G02X1269002Y6994I-141J142D01*
G01X1268968Y6980D01*
X1164772D01*
G02X1164696Y6995I0J200D01*
G01X1164660Y7010D01*
X1164636Y7034D01*
X1097702D01*
G02X1097576Y7079I0J200D01*
G02X1097561Y7092I123J157D01*
G01X1094907Y9746D01*
G02X1094863Y9813I142J141D01*
G01X1094849Y9847D01*
Y72098D01*
G02X1095049Y72298I200J0D01*
G01X1098460D01*
G03X1104601Y75492I0J7501D01*
G02X1104728Y75574I164J-115D01*
G02X1104764Y75577I35J-197D01*
G01X1118098D01*
G03X1118240Y75636I0J200D01*
G01X1130677Y88073D01*
G02X1130727Y88109I140J-142D01*
G02X1130818Y88131I91J-178D01*
G01X1142317D01*
G02X1142443Y88086I0J-200D01*
G02X1142458Y88073I-123J-157D01*
G01X1144872Y85659D01*
G03X1145014Y85600I142J141D01*
G01X1172717D01*
G03X1172859Y85659I0J200D01*
G01X1174941Y87741D01*
G03X1175000Y87883I-141J142D01*
G01Y102817D01*
G03X1174941Y102959I-200J0D01*
G01X1174050Y103850D01*
G02X1174006Y103917I142J141D01*
G01X1173992Y103951D01*
Y132649D01*
G02X1174037Y132775I200J0D01*
G02X1174050Y132790I157J-123D01*
G01X1176742Y135482D01*
G02X1176792Y135518I140J-142D01*
G02X1176883Y135540I91J-178D01*
G01X1193757D01*
G03X1193899Y135599I0J200D01*
G01X1199765Y141465D01*
G03X1199824Y141607I-141J142D01*
G01Y190238D01*
G02X1199869Y190364I200J0D01*
G02X1199882Y190379I157J-123D01*
G01X1218941Y209438D01*
G03X1219000Y209580I-141J142D01*
G01Y269917D01*
G02X1219045Y270043I200J0D01*
G02X1219058Y270058I157J-123D01*
G01X1221442Y272442D01*
G02X1221492Y272478I140J-142D01*
G02X1221583Y272500I91J-178D01*
G01X1277832D01*
G02X1277958Y272455I0J-200D01*
G02X1277973Y272442I-123J-157D01*
G01X1281129Y269286D01*
G02X1281165Y269236I-142J-140D01*
G02X1281187Y269145I-178J-91D01*
G01Y19239D01*
G02X1281142Y19113I-200J0D01*
G02X1281129Y19098I-157J123D01*
G37*
G36*
G01X1072600Y98300D02*
X1077984D01*
X1078161Y98123D01*
Y90281D01*
X1077780Y89900D01*
X1072400D01*
X1072200Y90100D01*
Y97900D01*
X1072600Y98300D01*
G37*
G36*
G01X1083628Y129184D02*
X1088645D01*
X1092014D01*
X1092664Y129834D01*
Y134127D01*
X1092528Y134264D01*
X1084881D01*
X1083185Y132568D01*
Y129627D01*
X1083628Y129184D01*
G37*
G36*
G01X1102610Y174572D02*
X1106125D01*
X1106697Y174000D01*
X1110272D01*
X1110523Y174251D01*
X1118046D01*
X1118192Y174105D01*
Y173173D01*
X1117988Y172969D01*
X1114107D01*
G03X1113368Y173158I-739J-1350D01*
G03X1112629Y172969I0J-1539D01*
G01X1112569D01*
X1112466Y172866D01*
G03X1112121Y172521I902J-1247D01*
G01X1111600Y172000D01*
X1109900D01*
X1108800Y170900D01*
Y169000D01*
X1106617Y166817D01*
X1099914D01*
X1099739Y166992D01*
Y169966D01*
X1102333Y172560D01*
Y174295D01*
X1102610Y174572D01*
G37*
G36*
G01X1096508Y191248D02*
X1098337Y189419D01*
Y178486D01*
X1098686Y178137D01*
X1112999D01*
X1114311Y176825D01*
X1118084D01*
X1118217Y176958D01*
Y178051D01*
X1113902Y182366D01*
X1110098D01*
X1101585Y190879D01*
Y196755D01*
Y198300D01*
Y203841D01*
X1100721Y204705D01*
X1097061D01*
X1096508Y204152D01*
Y191248D01*
G37*
G36*
G01X1086734Y202392D02*
X1093276D01*
X1093468Y202200D01*
Y196766D01*
X1093263Y196561D01*
X1086734D01*
X1086384Y196911D01*
Y202042D01*
X1086734Y202392D01*
G37*
G36*
G01X1099958Y376748D02*
X1162482D01*
X1175352D01*
X1176800Y375300D01*
Y352300D01*
X1171500Y347000D01*
X1166810D01*
X1163710Y343900D01*
Y331300D01*
X1163000Y330590D01*
Y327100D01*
X1164600Y325500D01*
X1176500D01*
X1177000Y325000D01*
Y310590D01*
X1175710Y309300D01*
Y306600D01*
X1177000Y305310D01*
Y243000D01*
X1173500Y239500D01*
X1100467D01*
X1099172Y240795D01*
Y375962D01*
X1099958Y376748D01*
G37*
G36*
G01X1101287Y520000D02*
X1162060D01*
X1163920Y518140D01*
Y472665D01*
G03Y469835I1271J-1415D01*
G01Y466820D01*
X1165890Y464850D01*
X1176250D01*
X1177000Y464100D01*
Y452857D01*
X1175868Y451725D01*
Y449142D01*
X1177000Y448010D01*
Y383500D01*
X1175499Y381999D01*
X1100011D01*
X1099265Y382745D01*
Y517978D01*
X1101287Y520000D01*
G37*
G36*
G01X1097500Y532180D02*
Y566200D01*
X1099900Y568600D01*
X1125100D01*
X1128100Y565600D01*
Y531890D01*
X1126460Y530250D01*
X1099430D01*
X1097500Y532180D01*
G37*
G36*
G01X1135873Y126464D02*
Y120289D01*
X1135515Y119931D01*
X1135384Y119800D01*
X1120985D01*
X1120854Y119931D01*
X1120547Y120238D01*
Y126531D01*
X1120737Y126721D01*
X1135616D01*
X1135873Y126464D01*
G37*
G36*
G01X1137700Y196315D02*
X1157885D01*
X1158200Y196000D01*
Y190953D01*
X1157912Y190665D01*
X1143085D01*
X1141302Y188882D01*
X1137634Y185214D01*
Y176977D01*
X1141162Y173449D01*
Y159079D01*
X1145560Y154681D01*
Y151773D01*
X1145245Y151458D01*
X1136506D01*
X1136098Y151866D01*
Y158855D01*
X1135143Y159810D01*
Y175782D01*
X1136288Y176927D01*
Y188488D01*
X1137400Y189600D01*
Y196015D01*
X1137700Y196315D01*
G37*
G36*
G01X1146082Y164347D02*
X1151162D01*
X1152901Y162608D01*
X1165534D01*
X1165662Y162480D01*
Y157759D01*
X1165533Y157630D01*
X1155134D01*
X1149611Y163153D01*
X1146066D01*
X1145946Y163273D01*
Y164211D01*
X1146082Y164347D01*
G37*
G36*
G01X1146100Y167066D02*
X1151139D01*
X1153338Y169265D01*
X1165466D01*
X1165686Y169485D01*
Y174113D01*
Y176838D01*
X1165280Y177244D01*
X1159189D01*
X1156290Y174345D01*
X1150295Y168350D01*
X1146094D01*
X1145968Y168224D01*
Y167198D01*
X1146100Y167066D01*
G37*
G36*
G01X1199100Y479100D02*
X1257500D01*
X1261500Y475100D01*
Y303500D01*
X1258500Y300500D01*
X1214341D01*
X1204500Y290659D01*
Y220000D01*
X1188134Y203634D01*
X1151966D01*
X1151800Y203800D01*
Y213800D01*
X1152300Y214300D01*
X1167564D01*
X1182164Y228900D01*
Y305156D01*
X1183592Y306584D01*
Y309284D01*
X1182171Y310705D01*
Y324871D01*
X1182800Y325500D01*
X1194700D01*
X1195620Y326420D01*
Y343780D01*
X1192400Y347000D01*
X1187500D01*
X1182171Y352329D01*
Y447790D01*
X1183703Y449322D01*
Y451482D01*
X1182171Y453014D01*
Y463950D01*
X1183071Y464850D01*
X1194300D01*
X1196100Y466650D01*
Y476100D01*
X1199100Y479100D01*
G37*
G36*
G01X1189998Y182898D02*
X1190450Y182447D01*
Y151650D01*
X1190150Y151350D01*
X1176850D01*
X1176200Y152000D01*
Y182500D01*
X1176598Y182898D01*
X1189998D01*
G37*
%LPC*%
G75*
G36*
G01X149300Y217317D02*
X150021Y218038D01*
X156211D01*
X156816Y217433D01*
Y211079D01*
X156073Y210336D01*
X150734D01*
X149300Y211770D01*
Y217317D01*
G37*
G36*
G01X733214Y326884D02*
G03X733861I323J236D01*
G02X735075Y327502I1214J-883D01*
G02Y324498I0J-1502D01*
G02X733861Y325116I0J1501D01*
G03X733214I-324J-236D01*
G02X732000Y324498I-1214J883D01*
G02Y327502I0J1502D01*
G02X733214Y326884I0J-1501D01*
G37*
G36*
G01X733169Y336842D02*
G03X733831I331J224D01*
G02X735075Y337502I1244J-842D01*
G02Y334498I0J-1502D01*
G02X733831Y335158I0J1502D01*
G03X733169I-331J-224D01*
G02X731925Y334498I-1244J842D01*
G02Y337502I0J1502D01*
G02X733169Y336842I0J-1502D01*
G37*
G36*
G01X697476Y354356D02*
G02X697198Y356000I4724J1644D01*
G02X702200Y361002I5002J0D01*
G02X705825Y359446I-1J-5002D01*
G01X705858Y359412D01*
X705945Y359380D01*
X706356Y359426D01*
X706435Y359477D01*
X706459Y359518D01*
G02X707750Y360252I1291J-768D01*
G02Y357248I0J-1502D01*
G02X707579Y357258I2J1502D01*
G01X707532Y357263D01*
X707444Y357232D01*
X707158Y356932D01*
X707131Y356844D01*
X707138Y356797D01*
G02X707202Y356000I-4938J-798D01*
G02X702200Y350998I-5002J0D01*
G02X699631Y351708I0J5003D01*
G01X699599Y351727D01*
X699527Y351740D01*
X699189Y351673D01*
X699128Y351634D01*
X699105Y351603D01*
G02X697900Y350998I-1205J898D01*
G02X696398Y352500I0J1502D01*
G02X697267Y353862I1502J0D01*
G01X697301Y353878D01*
X697352Y353930D01*
X697486Y354247D01*
X697488Y354320D01*
X697476Y354356D01*
G37*
G36*
G01X563279Y450414D02*
G02X564498Y450502I1220J-8414D01*
G01X564500D01*
G02Y433498I0J-8502D01*
G01X564498D01*
G02X563279Y433586I1J8502D01*
G03X563221I-29J-198D01*
G02X562002Y433498I-1220J8414D01*
G01X562000D01*
G02Y450502I0J8502D01*
G01X562002D01*
G02X563221Y450414I-1J-8502D01*
G03X563279I29J198D01*
G37*
G36*
G01X248668Y481856D02*
G02X249169Y482356I501J-1D01*
G01X258469D01*
G02X258970Y481854I-1J-502D01*
G01Y472552D01*
G02X258469Y472052I-501J1D01*
G01X249169D01*
G02X248668Y472554I1J502D01*
G01Y481856D01*
G37*
G36*
G01X406148D02*
G02X406649Y482356I501J-1D01*
G01X415949D01*
G02X416450Y481854I-1J-502D01*
G01Y472552D01*
G02X415949Y472052I-501J1D01*
G01X406649D01*
G02X406148Y472554I1J502D01*
G01Y481856D01*
G37*
G36*
G01X563628Y481854D02*
G02X564130Y482356I502J0D01*
G01X573430D01*
G02X573932Y481854I0J-502D01*
G01Y472554D01*
G02X573430Y472052I-502J0D01*
G01X564130D01*
G02X563628Y472554I0J502D01*
G01Y481854D01*
G37*
G36*
G01X721110Y481856D02*
G02X721611Y482356I501J-1D01*
G01X730911D01*
G02X731412Y481854I-1J-502D01*
G01Y472552D01*
G02X730911Y472052I-501J1D01*
G01X721611D01*
G02X721110Y472554I1J502D01*
G01Y481856D01*
G37*
G36*
G01X176373Y526943D02*
G02X176515Y527002I142J-141D01*
G01X187563D01*
G02X187705Y526943I0J-200D01*
G01X192481Y522166D01*
G02X192540Y522024I-141J-142D01*
G01Y494476D01*
G02X192481Y494334I-200J0D01*
G01X187705Y489557D01*
G02X187563Y489498I-142J141D01*
G01X176515D01*
G02X176373Y489557I0J200D01*
G01X172500Y493431D01*
Y523069D01*
X176373Y526943D01*
G37*
G36*
G01X224373D02*
G02X224515Y527002I142J-141D01*
G01X235563D01*
G02X235705Y526943I0J-200D01*
G01X240481Y522166D01*
G02X240540Y522024I-141J-142D01*
G01Y494476D01*
G02X240481Y494334I-200J0D01*
G01X235705Y489557D01*
G02X235563Y489498I-142J141D01*
G01X227827D01*
G03X227630Y489330I1J-200D01*
G01X227555Y488869D01*
X227630Y488743D01*
X227700Y488720D01*
G02X235971Y477204I-3882J-11516D01*
G02X211667I-12152J0D01*
G02X223616Y489354I12152J0D01*
G01X223618D01*
G03X223798Y489479I-5J200D01*
G01X223937Y489820D01*
G03X223893Y490037I-185J75D01*
G01X220500Y493431D01*
Y523069D01*
X224373Y526943D01*
G37*
G36*
G01X272373D02*
G02X272515Y527002I142J-141D01*
G01X283563D01*
G02X283705Y526943I0J-200D01*
G01X288481Y522166D01*
G02X288540Y522024I-141J-142D01*
G01Y494476D01*
G02X288481Y494334I-200J0D01*
G01X283705Y489557D01*
G02X283563Y489498I-142J141D01*
G01X272515D01*
G02X272373Y489557I0J200D01*
G01X268500Y493431D01*
Y523069D01*
X272373Y526943D01*
G37*
G36*
G01X333853D02*
G02X333995Y527002I142J-141D01*
G01X345043D01*
G02X345185Y526943I0J-200D01*
G01X349961Y522166D01*
G02X350020Y522024I-141J-142D01*
G01Y494476D01*
G02X349961Y494334I-200J0D01*
G01X345185Y489557D01*
G02X345043Y489498I-142J141D01*
G01X333995D01*
G02X333853Y489557I0J200D01*
G01X330000Y493411D01*
Y523089D01*
X333853Y526943D01*
G37*
G36*
G01X381853D02*
G02X381995Y527002I142J-141D01*
G01X393043D01*
G02X393185Y526943I0J-200D01*
G01X397961Y522166D01*
G02X398020Y522024I-141J-142D01*
G01Y494476D01*
G02X397961Y494334I-200J0D01*
G01X393185Y489557D01*
G02X393043Y489498I-142J141D01*
G01X385307D01*
G03X385110Y489330I1J-200D01*
G01X385035Y488869D01*
X385110Y488743D01*
X385180Y488720D01*
G02X393451Y477204I-3882J-11516D01*
G02X369147I-12152J0D01*
G02X381096Y489354I12152J0D01*
G01X381098D01*
G03X381278Y489479I-5J200D01*
G01X381417Y489820D01*
G03X381373Y490037I-185J75D01*
G01X378000Y493411D01*
Y523089D01*
X381853Y526943D01*
G37*
G36*
G01X429853D02*
G02X429995Y527002I142J-141D01*
G01X441043D01*
G02X441185Y526943I0J-200D01*
G01X445961Y522166D01*
G02X446020Y522024I-141J-142D01*
G01Y494476D01*
G02X445961Y494334I-200J0D01*
G01X441185Y489557D01*
G02X441043Y489498I-142J141D01*
G01X429995D01*
G02X429853Y489557I0J200D01*
G01X426000Y493411D01*
Y523089D01*
X429853Y526943D01*
G37*
G36*
G01X491334D02*
G02X491476Y527002I142J-141D01*
G01X502524D01*
G02X502666Y526943I0J-200D01*
G01X507443Y522166D01*
G02X507502Y522024I-141J-142D01*
G01Y494476D01*
G02X507443Y494334I-200J0D01*
G01X502666Y489557D01*
G02X502524Y489498I-142J141D01*
G01X491476D01*
G02X491334Y489557I0J200D01*
G01X487500Y493391D01*
Y523109D01*
X491334Y526943D01*
G37*
G36*
G01X539334D02*
G02X539476Y527002I142J-141D01*
G01X550524D01*
G02X550666Y526943I0J-200D01*
G01X555443Y522166D01*
G02X555502Y522024I-141J-142D01*
G01Y494476D01*
G02X555443Y494334I-200J0D01*
G01X550666Y489557D01*
G02X550524Y489498I-142J141D01*
G01X542788D01*
G03X542591Y489330I1J-200D01*
G01X542516Y488869D01*
X542591Y488743D01*
X542661Y488720D01*
G02X550932Y477204I-3882J-11516D01*
G02X526628I-12152J0D01*
G02X538577Y489354I12152J0D01*
G01X538579D01*
G03X538759Y489479I-5J200D01*
G01X538898Y489820D01*
G03X538854Y490037I-185J75D01*
G01X535500Y493391D01*
Y523109D01*
X539334Y526943D01*
G37*
G36*
G01X587334D02*
G02X587476Y527002I142J-141D01*
G01X598524D01*
G02X598666Y526943I0J-200D01*
G01X603443Y522166D01*
G02X603502Y522024I-141J-142D01*
G01Y494476D01*
G02X603443Y494334I-200J0D01*
G01X598666Y489557D01*
G02X598524Y489498I-142J141D01*
G01X587476D01*
G02X587334Y489557I0J200D01*
G01X583500Y493391D01*
Y523109D01*
X587334Y526943D01*
G37*
G36*
G01X648815D02*
G02X648957Y527002I142J-141D01*
G01X660005D01*
G02X660147Y526943I0J-200D01*
G01X664923Y522166D01*
G02X664982Y522024I-141J-142D01*
G01Y494476D01*
G02X664923Y494334I-200J0D01*
G01X660147Y489557D01*
G02X660005Y489498I-142J141D01*
G01X648957D01*
G02X648815Y489557I0J200D01*
G01X645000Y493373D01*
Y523127D01*
X648815Y526943D01*
G37*
G36*
G01X696815D02*
G02X696957Y527002I142J-141D01*
G01X708005D01*
G02X708147Y526943I0J-200D01*
G01X712923Y522166D01*
G02X712982Y522024I-141J-142D01*
G01Y494476D01*
G02X712923Y494334I-200J0D01*
G01X708147Y489557D01*
G02X708005Y489498I-142J141D01*
G01X700269D01*
G03X700072Y489330I1J-200D01*
G01X699997Y488869D01*
X700072Y488743D01*
X700142Y488720D01*
G02X708413Y477204I-3882J-11516D01*
G02X684109I-12152J0D01*
G02X696058Y489354I12152J0D01*
G01X696060D01*
G03X696240Y489479I-5J200D01*
G01X696379Y489820D01*
G03X696335Y490037I-185J75D01*
G01X693000Y493373D01*
Y523127D01*
X696815Y526943D01*
G37*
G36*
G01X744815D02*
G02X744957Y527002I142J-141D01*
G01X756005D01*
G02X756147Y526943I0J-200D01*
G01X760924Y522166D01*
G02X760982Y522025I-142J-141D01*
G01Y494475D01*
G02X760924Y494334I-200J0D01*
G01X756147Y489557D01*
G02X756005Y489498I-142J141D01*
G01X744957D01*
G02X744815Y489557I0J200D01*
G01X744375Y489997D01*
G03X744297Y490075I-175J-97D01*
G01X741000Y493372D01*
Y523128D01*
X744815Y526943D01*
G37*
G36*
G01X161938Y542102D02*
G02X162439Y542602I501J-1D01*
G01X168639D01*
G02X169140Y542100I-1J-502D01*
G01Y535898D01*
G02X168639Y535398I-501J1D01*
G01X162439D01*
G02X161938Y535900I1J502D01*
G01Y542102D01*
G37*
G36*
G01X209938D02*
G02X210439Y542602I501J-1D01*
G01X216639D01*
G02X217140Y542100I-1J-502D01*
G01Y535898D01*
G02X216639Y535398I-501J1D01*
G01X210439D01*
G02X209938Y535900I1J502D01*
G01Y542102D01*
G37*
G36*
G01X257938D02*
G02X258439Y542602I501J-1D01*
G01X264639D01*
G02X265140Y542100I-1J-502D01*
G01Y535898D01*
G02X264639Y535398I-501J1D01*
G01X258439D01*
G02X257938Y535900I1J502D01*
G01Y542102D01*
G37*
G36*
G01X319418D02*
G02X319919Y542602I501J-1D01*
G01X326119D01*
G02X326620Y542100I-1J-502D01*
G01Y535898D01*
G02X326119Y535398I-501J1D01*
G01X319919D01*
G02X319418Y535900I1J502D01*
G01Y542102D01*
G37*
G36*
G01X367418D02*
G02X367919Y542602I501J-1D01*
G01X374119D01*
G02X374620Y542100I-1J-502D01*
G01Y535898D01*
G02X374119Y535398I-501J1D01*
G01X367919D01*
G02X367418Y535900I1J502D01*
G01Y542102D01*
G37*
G36*
G01X415418D02*
G02X415919Y542602I501J-1D01*
G01X422119D01*
G02X422620Y542100I-1J-502D01*
G01Y535898D01*
G02X422119Y535398I-501J1D01*
G01X415919D01*
G02X415418Y535900I1J502D01*
G01Y542102D01*
G37*
G36*
G01X476898Y542100D02*
G02X477400Y542602I502J0D01*
G01X483600D01*
G02X484102Y542100I0J-502D01*
G01Y535900D01*
G02X483600Y535398I-502J0D01*
G01X477400D01*
G02X476898Y535900I0J502D01*
G01Y542100D01*
G37*
G36*
G01X524898D02*
G02X525400Y542602I502J0D01*
G01X531600D01*
G02X532102Y542100I0J-502D01*
G01Y535900D01*
G02X531600Y535398I-502J0D01*
G01X525400D01*
G02X524898Y535900I0J502D01*
G01Y542100D01*
G37*
G36*
G01X572898D02*
G02X573400Y542602I502J0D01*
G01X579600D01*
G02X580102Y542100I0J-502D01*
G01Y535900D01*
G02X579600Y535398I-502J0D01*
G01X573400D01*
G02X572898Y535900I0J502D01*
G01Y542100D01*
G37*
G36*
G01X634380Y542102D02*
G02X634881Y542602I501J-1D01*
G01X641081D01*
G02X641582Y542100I-1J-502D01*
G01Y535898D01*
G02X641081Y535398I-501J1D01*
G01X634881D01*
G02X634380Y535900I1J502D01*
G01Y542102D01*
G37*
G36*
G01X682380D02*
G02X682881Y542602I501J-1D01*
G01X689081D01*
G02X689582Y542100I-1J-502D01*
G01Y535898D01*
G02X689081Y535398I-501J1D01*
G01X682881D01*
G02X682380Y535900I1J502D01*
G01Y542102D01*
G37*
G36*
G01X730380D02*
G02X730881Y542602I501J-1D01*
G01X737081D01*
G02X737582Y542100I-1J-502D01*
G01Y535898D01*
G02X737081Y535398I-501J1D01*
G01X730881D01*
G02X730380Y535900I1J502D01*
G01Y542102D01*
G37*
G36*
G01X659017Y284316D02*
X659045Y284345D01*
G02X666261Y287356I7216J-7141D01*
G02X676413Y277204I0J-10152D01*
G01Y277202D01*
G02X675631Y273296I-10152J1D01*
G03X675722Y273042I184J-77D01*
G02X676460Y272588I-3083J-5838D01*
G03X676692I116J163D01*
G02X684334I3821J-5384D01*
G03X684566I116J163D01*
G02X692208I3821J-5384D01*
G03X692440I116J163D01*
G02X700082I3821J-5384D01*
G03X700314I116J163D01*
G02X707956I3821J-5384D01*
G03X708188I116J163D01*
G02X715830I3821J-5384D01*
G03X716062I116J163D01*
G02X719878Y273806I3821J-5384D01*
G01X719930D01*
X720019Y273855D01*
X720256Y274228D01*
X720262Y274329D01*
X720240Y274376D01*
G02X719609Y277204I6022J2828D01*
G02X726261Y270552I6652J0D01*
G01X726184D01*
X726094Y270504D01*
X725856Y270132D01*
X725849Y270031D01*
X725871Y269984D01*
G02X726485Y267204I-5988J-2780D01*
G02X725296Y263425I-6602J1D01*
G03X725289Y263415I160J-120D01*
G02X719883Y260602I-5406J3788D01*
G02X719487Y260614I2J6602D01*
G01X719421Y260618D01*
X719311Y260547D01*
X719128Y260068D01*
X719162Y259942D01*
X719214Y259902D01*
G02X721102Y255987I-3115J-3915D01*
G02X718142Y251421I-5002J0D01*
G01Y233635D01*
G02X718083Y233494I-200J1D01*
G01X715376Y230787D01*
G02X715235Y230728I-142J141D01*
G01X705772D01*
X703440Y233060D01*
Y241636D01*
X704301Y242497D01*
Y252695D01*
X704728Y253122D01*
X711293D01*
G03X711464Y253217I1J200D01*
G01X711670Y253554D01*
X711674Y253657D01*
X711649Y253704D01*
G02X711098Y255986I4451J2282D01*
G01Y255987D01*
G02X713021Y259929I5002J0D01*
G01X713074Y259970D01*
X713108Y260100D01*
X712913Y260580D01*
X712797Y260649D01*
X712731Y260642D01*
G02X712009Y260602I-726J6562D01*
G02X708188Y261820I0J6602D01*
G03X707956I-116J-163D01*
G02X705100Y260673I-3821J5384D01*
G01X705055Y260666D01*
X704982Y260617D01*
X704837Y260379D01*
G02X705043Y258960I-4797J-1421D01*
G02X705042Y258877I-5003J19D01*
G02X705056Y258509I-4988J-374D01*
G02X695052I-5002J0D01*
G01Y258512D01*
G02Y258569I5002J29D01*
G02X695037Y258960I4988J387D01*
G02X695267Y260460I5003J0D01*
G01X695154Y260657D01*
X695083Y260708D01*
X695040Y260716D01*
G02X692440Y261820I1221J6488D01*
G03X692208I-116J-163D01*
G02X688387Y260602I-3821J5384D01*
G02X687928Y260618I0J6602D01*
G01X687886Y260621D01*
G02X684566Y261820I501J6583D01*
G03X684334I-116J-163D01*
G02X676692I-3821J5384D01*
G03X676460I-116J-163D01*
G02X672639Y260602I-3821J5384D01*
G02X666045Y266870I0J6602D01*
G03X665854Y267060I-200J-10D01*
G02X659045Y270063I407J10144D01*
G01X659017Y270092D01*
X658944Y270122D01*
X658578D01*
X658505Y270092D01*
X658477Y270063D01*
G02X651261Y267052I-7216J7141D01*
G02Y287356I0J10152D01*
G02X658477Y284345I0J-10152D01*
G01X658505Y284316D01*
X658578Y284286D01*
X658944D01*
X659017Y284316D01*
G37*
G36*
G01X546819Y252571D02*
X547370Y253122D01*
X557954D01*
G02X558095Y253063I-1J-200D01*
G01X560602Y250556D01*
G02X560660Y250415I-142J-141D01*
G01Y233635D01*
G02X560602Y233494I-200J0D01*
G01X557895Y230787D01*
G02X557754Y230728I-142J141D01*
G01X548291D01*
X545962Y233057D01*
Y241627D01*
X546819Y242484D01*
Y252571D01*
G37*
G36*
G01X393320Y251508D02*
X393934Y252122D01*
X404454D01*
G02X404595Y252063I-1J-200D01*
G01X407102Y249556D01*
G02X407160Y249415I-142J-141D01*
G01Y232635D01*
G02X407102Y232494I-200J0D01*
G01X404395Y229787D01*
G02X404254Y229728I-142J141D01*
G01X394791D01*
X392461Y232058D01*
Y240627D01*
X393320Y241486D01*
Y251508D01*
G37*
G36*
G01X237318Y252087D02*
X237853Y252622D01*
X248454D01*
G02X248595Y252563I-1J-200D01*
G01X251102Y250056D01*
G02X251160Y249915I-142J-141D01*
G01Y233135D01*
G02X251102Y232994I-200J0D01*
G01X248395Y230287D01*
G02X248254Y230228I-142J141D01*
G01X238791D01*
X236459Y232560D01*
Y241118D01*
X237318Y241977D01*
Y252087D01*
G37*
G36*
G01X425204Y23542D02*
G02Y70946I0J23702D01*
G01X511804D01*
G02Y23542I0J-23702D01*
G01X425204D01*
G37*
G36*
G01X302586Y165525D02*
G03X302839Y165500I142J141D01*
G02X306752Y166694I3913J-5815D01*
G02X313761Y159685I0J-7009D01*
G02X311856Y154881I-7010J0D01*
G03X311801Y154744I145J-138D01*
G01Y154626D01*
G03X311856Y154489I200J1D01*
G02Y144881I-5105J-4804D01*
G03X311801Y144744I145J-138D01*
G01Y144626D01*
G03X311856Y144489I200J1D01*
G02Y134881I-5105J-4804D01*
G03X311801Y134744I145J-138D01*
G01Y134626D01*
G03X311856Y134489I200J1D01*
G02X313761Y129685I-5105J-4804D01*
G02X306752Y122676I-7009J0D01*
G02X301948Y124581I0J7010D01*
G03X301811Y124636I-138J-145D01*
G01X301693D01*
G03X301556Y124581I1J-200D01*
G02X296752Y122676I-4804J5105D01*
G02X289743Y129685I0J7009D01*
G02X291648Y134489I7010J0D01*
G03X291703Y134626I-145J138D01*
G01Y134744D01*
G03X291648Y134881I-200J-1D01*
G02Y144489I5105J4804D01*
G03X291703Y144626I-145J138D01*
G01Y144744D01*
G03X291648Y144881I-200J-1D01*
G02X289743Y149685I5105J4804D01*
G02X290937Y153598I7009J0D01*
G03X290912Y153851I-166J111D01*
G02X289743Y156677I2833J2826D01*
G01Y162693D01*
G02X293744Y166694I4002J-1D01*
G01X299760D01*
G02X302586Y165525I0J-4002D01*
G37*
G36*
G01X336811Y164734D02*
G03X336948Y164789I-1J200D01*
G02X341752Y166694I4804J-5105D01*
G02X348761Y159685I0J-7009D01*
G02X346856Y154881I-7010J0D01*
G03X346801Y154744I145J-138D01*
G01Y154626D01*
G03X346856Y154489I200J1D01*
G02Y144881I-5105J-4804D01*
G03X346801Y144744I145J-138D01*
G01Y144626D01*
G03X346856Y144489I200J1D01*
G02Y134881I-5105J-4804D01*
G03X346801Y134744I145J-138D01*
G01Y134626D01*
G03X346856Y134489I200J1D01*
G02X348761Y129685I-5105J-4804D01*
G02X341752Y122676I-7009J0D01*
G02X336948Y124581I0J7010D01*
G03X336811Y124636I-138J-145D01*
G01X336693D01*
G03X336556Y124581I1J-200D01*
G02X331752Y122676I-4804J5105D01*
G02X324743Y129685I0J7009D01*
G02X326648Y134489I7010J0D01*
G03X326703Y134626I-145J138D01*
G01Y134744D01*
G03X326648Y134881I-200J-1D01*
G02Y144489I5105J4804D01*
G03X326703Y144626I-145J138D01*
G01Y144744D01*
G03X326648Y144881I-200J-1D01*
G02Y154489I5105J4804D01*
G03X326703Y154626I-145J138D01*
G01Y154744D01*
G03X326648Y154881I-200J-1D01*
G02X324743Y159685I5105J4804D01*
G02X331752Y166694I7009J0D01*
G02X336556Y164789I0J-7010D01*
G03X336693Y164734I138J145D01*
G01X336811D01*
G37*
G36*
G01X371811D02*
G03X371948Y164789I-1J200D01*
G02X376752Y166694I4804J-5105D01*
G02X383761Y159685I0J-7009D01*
G02X381856Y154881I-7010J0D01*
G03X381801Y154744I145J-138D01*
G01Y154626D01*
G03X381856Y154489I200J1D01*
G02Y144881I-5105J-4804D01*
G03X381801Y144744I145J-138D01*
G01Y144626D01*
G03X381856Y144489I200J1D01*
G02Y134881I-5105J-4804D01*
G03X381801Y134744I145J-138D01*
G01Y134626D01*
G03X381856Y134489I200J1D01*
G02X383761Y129685I-5105J-4804D01*
G02X376752Y122676I-7009J0D01*
G02X371948Y124581I0J7010D01*
G03X371811Y124636I-138J-145D01*
G01X371693D01*
G03X371556Y124581I1J-200D01*
G02X366752Y122676I-4804J5105D01*
G02X359743Y129685I0J7009D01*
G02X361648Y134489I7010J0D01*
G03X361703Y134626I-145J138D01*
G01Y134744D01*
G03X361648Y134881I-200J-1D01*
G02Y144489I5105J4804D01*
G03X361703Y144626I-145J138D01*
G01Y144744D01*
G03X361648Y144881I-200J-1D01*
G02Y154489I5105J4804D01*
G03X361703Y154626I-145J138D01*
G01Y154744D01*
G03X361648Y154881I-200J-1D01*
G02X359743Y159685I5105J4804D01*
G02X366752Y166694I7009J0D01*
G02X371556Y164789I0J-7010D01*
G03X371693Y164734I138J145D01*
G01X371811D01*
G37*
G36*
G01X597444Y210503D02*
G02X597585Y210562I142J-141D01*
G01X606715D01*
G02X606856Y210503I-1J-200D01*
G01X609523Y207836D01*
G02X609582Y207695I-141J-142D01*
G01Y192275D01*
G02X609523Y192134I-200J1D01*
G01X606926Y189537D01*
G02X606785Y189478I-142J141D01*
G01X597535D01*
G02X597394Y189537I1J200D01*
G01X596019Y190912D01*
Y209170D01*
G02X596735Y209799I2980J-2671D01*
G01X596750Y209809D01*
X597444Y210503D01*
G37*
G36*
G01X618944D02*
G02X619085Y210562I142J-141D01*
G01X628215D01*
G02X628356Y210503I-1J-200D01*
G01X631023Y207836D01*
G02X631082Y207695I-141J-142D01*
G01Y192275D01*
G02X631023Y192134I-200J1D01*
G01X628426Y189537D01*
G02X628285Y189478I-142J141D01*
G01X619035D01*
G02X618894Y189537I1J200D01*
G01X617519Y190912D01*
Y209170D01*
G02X618235Y209799I2980J-2671D01*
G01X618250Y209809D01*
X618944Y210503D01*
G37*
G36*
G01X640444D02*
G02X640585Y210562I142J-141D01*
G01X649715D01*
G02X649856Y210503I-1J-200D01*
G01X652523Y207836D01*
G02X652582Y207695I-141J-142D01*
G01Y192275D01*
G02X652523Y192134I-200J1D01*
G01X649926Y189537D01*
G02X649785Y189478I-142J141D01*
G01X640535D01*
G02X640394Y189537I1J200D01*
G01X639019Y190912D01*
Y209170D01*
G02X639735Y209799I2980J-2671D01*
G01X639750Y209809D01*
X640444Y210503D01*
G37*
G36*
G01X661944D02*
G02X662085Y210562I142J-141D01*
G01X671215D01*
G02X671356Y210503I-1J-200D01*
G01X674023Y207836D01*
G02X674082Y207695I-141J-142D01*
G01Y192275D01*
G02X674023Y192134I-200J1D01*
G01X671426Y189537D01*
G02X671285Y189478I-142J141D01*
G01X662035D01*
G02X661894Y189537I1J200D01*
G01X660519Y190912D01*
Y209170D01*
G02X661235Y209799I2980J-2671D01*
G01X661250Y209809D01*
X661944Y210503D01*
G37*
G36*
G01X683444D02*
G02X683585Y210562I142J-141D01*
G01X692715D01*
G02X692856Y210503I-1J-200D01*
G01X695523Y207836D01*
G02X695582Y207695I-141J-142D01*
G01Y192275D01*
G02X695523Y192134I-200J1D01*
G01X692926Y189537D01*
G02X692785Y189478I-142J141D01*
G01X683535D01*
G02X683394Y189537I1J200D01*
G01X682019Y190912D01*
Y209170D01*
G02X682735Y209799I2980J-2671D01*
G01X682750Y209809D01*
X683444Y210503D01*
G37*
G36*
G01X704934D02*
G02X705075Y210562I142J-141D01*
G01X714205D01*
G02X714346Y210503I-1J-200D01*
G01X717013Y207836D01*
G02X717072Y207695I-141J-142D01*
G01Y192275D01*
G02X717013Y192134I-200J1D01*
G01X714416Y189537D01*
G02X714275Y189478I-142J141D01*
G01X705025D01*
G02X704884Y189537I1J200D01*
G01X703509Y190912D01*
Y209170D01*
G02X704225Y209799I2980J-2671D01*
G01X704240Y209809D01*
X704934Y210503D01*
G37*
G36*
G01X726434D02*
G02X726575Y210562I142J-141D01*
G01X735705D01*
G02X735846Y210503I-1J-200D01*
G01X738513Y207836D01*
G02X738572Y207695I-141J-142D01*
G01Y192275D01*
G02X738513Y192134I-200J1D01*
G01X735916Y189537D01*
G02X735775Y189478I-142J141D01*
G01X726525D01*
G02X726384Y189537I1J200D01*
G01X725009Y190912D01*
Y209170D01*
G02X725725Y209799I2980J-2671D01*
G01X725740Y209809D01*
X726434Y210503D01*
G37*
G36*
G01X289944Y211003D02*
G02X290085Y211062I142J-141D01*
G01X299215D01*
G02X299356Y211003I-1J-200D01*
G01X302023Y208336D01*
G02X302082Y208195I-141J-142D01*
G01Y192775D01*
G02X302023Y192634I-200J1D01*
G01X299426Y190037D01*
G02X299285Y189978I-142J141D01*
G01X290035D01*
G02X289894Y190037I1J200D01*
G01X289218Y190713D01*
X289204Y190723D01*
G02X288519Y191331I2296J3277D01*
G01Y209670D01*
G02X289235Y210299I2980J-2671D01*
G01X289250Y210309D01*
X289944Y211003D01*
G37*
G36*
G01X311444D02*
G02X311585Y211062I142J-141D01*
G01X320715D01*
G02X320856Y211003I-1J-200D01*
G01X323523Y208336D01*
G02X323582Y208195I-141J-142D01*
G01Y192775D01*
G02X323523Y192634I-200J1D01*
G01X320926Y190037D01*
G02X320785Y189978I-142J141D01*
G01X311535D01*
G02X311394Y190037I1J200D01*
G01X310718Y190713D01*
X310704Y190723D01*
G02X310019Y191331I2296J3277D01*
G01Y209670D01*
G02X310735Y210299I2980J-2671D01*
G01X310750Y210309D01*
X311444Y211003D01*
G37*
G36*
G01X332944D02*
G02X333085Y211062I142J-141D01*
G01X342215D01*
G02X342356Y211003I-1J-200D01*
G01X345023Y208336D01*
G02X345082Y208195I-141J-142D01*
G01Y192775D01*
G02X345023Y192634I-200J1D01*
G01X342426Y190037D01*
G02X342285Y189978I-142J141D01*
G01X333035D01*
G02X332894Y190037I1J200D01*
G01X332218Y190713D01*
X332204Y190723D01*
G02X331519Y191331I2296J3277D01*
G01Y209670D01*
G02X332235Y210299I2980J-2671D01*
G01X332250Y210309D01*
X332944Y211003D01*
G37*
G36*
G01X354444D02*
G02X354585Y211062I142J-141D01*
G01X363715D01*
G02X363856Y211003I-1J-200D01*
G01X366523Y208336D01*
G02X366582Y208195I-141J-142D01*
G01Y192775D01*
G02X366523Y192634I-200J1D01*
G01X363926Y190037D01*
G02X363785Y189978I-142J141D01*
G01X354535D01*
G02X354394Y190037I1J200D01*
G01X353718Y190713D01*
X353704Y190723D01*
G02X353019Y191331I2296J3277D01*
G01Y209670D01*
G02X353735Y210299I2980J-2671D01*
G01X353750Y210309D01*
X354444Y211003D01*
G37*
G36*
G01X375944D02*
G02X376085Y211062I142J-141D01*
G01X385215D01*
G02X385356Y211003I-1J-200D01*
G01X388023Y208336D01*
G02X388082Y208195I-141J-142D01*
G01Y192775D01*
G02X388023Y192634I-200J1D01*
G01X385426Y190037D01*
G02X385285Y189978I-142J141D01*
G01X376035D01*
G02X375894Y190037I1J200D01*
G01X374519Y191412D01*
Y209670D01*
G02X375235Y210299I2980J-2671D01*
G01X375250Y210309D01*
X375944Y211003D01*
G37*
G36*
G01X397444D02*
G02X397585Y211062I142J-141D01*
G01X406715D01*
G02X406856Y211003I-1J-200D01*
G01X409523Y208336D01*
G02X409582Y208195I-141J-142D01*
G01Y192775D01*
G02X409523Y192634I-200J1D01*
G01X406926Y190037D01*
G02X406785Y189978I-142J141D01*
G01X397535D01*
G02X397394Y190037I1J200D01*
G01X396019Y191412D01*
Y209670D01*
G02X396735Y210299I2980J-2671D01*
G01X396750Y210309D01*
X397444Y211003D01*
G37*
G36*
G01X418944D02*
G02X419085Y211062I142J-141D01*
G01X428215D01*
G02X428356Y211003I-1J-200D01*
G01X431023Y208336D01*
G02X431082Y208195I-141J-142D01*
G01Y192775D01*
G02X431023Y192634I-200J1D01*
G01X428426Y190037D01*
G02X428285Y189978I-142J141D01*
G01X419035D01*
G02X418894Y190037I1J200D01*
G01X417519Y191412D01*
Y209670D01*
G02X418235Y210299I2980J-2671D01*
G01X418250Y210309D01*
X418944Y211003D01*
G37*
G36*
G01X264498Y243000D02*
G02X265000Y243502I502J0D01*
G01X271000D01*
G02X271502Y243000I0J-502D01*
G01Y237000D01*
G02X271000Y236498I-502J0D01*
G01X265000D01*
G02X264498Y237000I0J502D01*
G01Y243000D01*
G37*
G36*
G01X308998D02*
G02X309500Y243502I502J0D01*
G01X315500D01*
G02X316002Y243000I0J-502D01*
G01Y237000D01*
G02X315500Y236498I-502J0D01*
G01X309500D01*
G02X308998Y237000I0J502D01*
G01Y243000D01*
G37*
G36*
G01X353498D02*
G02X354000Y243502I502J0D01*
G01X360000D01*
G02X360502Y243000I0J-502D01*
G01Y237000D01*
G02X360000Y236498I-502J0D01*
G01X354000D01*
G02X353498Y237000I0J502D01*
G01Y243000D01*
G37*
G36*
G01X424998D02*
G02X425500Y243502I502J0D01*
G01X431500D01*
G02X432002Y243000I0J-502D01*
G01Y237000D01*
G02X431500Y236498I-502J0D01*
G01X425500D01*
G02X424998Y237000I0J502D01*
G01Y243000D01*
G37*
G36*
G01X468998D02*
G02X469500Y243502I502J0D01*
G01X475500D01*
G02X476002Y243000I0J-502D01*
G01Y237000D01*
G02X475500Y236498I-502J0D01*
G01X469500D01*
G02X468998Y237000I0J502D01*
G01Y243000D01*
G37*
G36*
G01X512998D02*
G02X513500Y243502I502J0D01*
G01X519500D01*
G02X520002Y243000I0J-502D01*
G01Y237000D01*
G02X519500Y236498I-502J0D01*
G01X513500D01*
G02X512998Y237000I0J502D01*
G01Y243000D01*
G37*
G36*
G01X574998D02*
G02X575500Y243502I502J0D01*
G01X581500D01*
G02X582002Y243000I0J-502D01*
G01Y237000D01*
G02X581500Y236498I-502J0D01*
G01X575500D01*
G02X574998Y237000I0J502D01*
G01Y243000D01*
G37*
G36*
G01X618998D02*
G02X619500Y243502I502J0D01*
G01X625500D01*
G02X626002Y243000I0J-502D01*
G01Y237000D01*
G02X625500Y236498I-502J0D01*
G01X619500D01*
G02X618998Y237000I0J502D01*
G01Y243000D01*
G37*
G36*
G01X662998D02*
G02X663500Y243502I502J0D01*
G01X669500D01*
G02X670002Y243000I0J-502D01*
G01Y237000D01*
G02X669500Y236498I-502J0D01*
G01X663500D01*
G02X662998Y237000I0J502D01*
G01Y243000D01*
G37*
G36*
G01X732480Y243002D02*
G02X732981Y243502I501J-1D01*
G01X738981D01*
G02X739482Y243000I-1J-502D01*
G01Y236998D01*
G02X738981Y236498I-501J1D01*
G01X732981D01*
G02X732480Y237000I1J502D01*
G01Y243002D01*
G37*
G36*
G01X776480D02*
G02X776981Y243502I501J-1D01*
G01X782981D01*
G02X783482Y243000I-1J-502D01*
G01Y236998D01*
G02X782981Y236498I-501J1D01*
G01X776981D01*
G02X776480Y237000I1J502D01*
G01Y243002D01*
G37*
G36*
G01X820480D02*
G02X820981Y243502I501J-1D01*
G01X826981D01*
G02X827482Y243000I-1J-502D01*
G01Y236998D01*
G02X826981Y236498I-501J1D01*
G01X820981D01*
G02X820480Y237000I1J502D01*
G01Y243002D01*
G37*
G36*
G01X344055Y284316D02*
X344083Y284345D01*
G02X351299Y287356I7216J-7141D01*
G02X361451Y277204I0J-10152D01*
G01Y277202D01*
G02X360669Y273296I-10152J1D01*
G03X360760Y273042I184J-77D01*
G02X361498Y272588I-3083J-5838D01*
G03X361730I116J163D01*
G02X369372I3821J-5384D01*
G03X369604I116J163D01*
G02X377246I3821J-5384D01*
G03X377478I116J163D01*
G02X385120I3821J-5384D01*
G03X385352I116J163D01*
G02X392994I3821J-5384D01*
G03X393226I116J163D01*
G02X400868I3821J-5384D01*
G03X401100I116J163D01*
G02X404916Y273806I3821J-5384D01*
G01X404968D01*
X405057Y273855D01*
X405294Y274228D01*
X405300Y274329D01*
X405278Y274376D01*
G02X404647Y277204I6022J2828D01*
G02X411299Y270552I6652J0D01*
G01X411222D01*
X411132Y270504D01*
X410894Y270132D01*
X410887Y270031D01*
X410909Y269984D01*
G02X411523Y267204I-5988J-2780D01*
G02X404921Y260602I-6602J0D01*
G02X401100Y261820I0J6602D01*
G03X400868I-116J-163D01*
G02X393226I-3821J5384D01*
G03X392994I-116J-163D01*
G02X385352I-3821J5384D01*
G03X385120I-116J-163D01*
G02X377478I-3821J5384D01*
G03X377246I-116J-163D01*
G02X369604I-3821J5384D01*
G03X369372I-116J-163D01*
G02X361730I-3821J5384D01*
G03X361498I-116J-163D01*
G02X357677Y260602I-3821J5384D01*
G02X351083Y266870I0J6602D01*
G03X350892Y267060I-200J-10D01*
G02X344083Y270063I407J10144D01*
G01X344055Y270092D01*
X343982Y270122D01*
X343616D01*
X343543Y270092D01*
X343515Y270063D01*
G02X336299Y267052I-7216J7141D01*
G02Y287356I0J10152D01*
G02X343515Y284345I0J-10152D01*
G01X343543Y284316D01*
X343616Y284286D01*
X343982D01*
X344055Y284316D01*
G37*
G36*
G01X503520Y285887D02*
G03X503525Y285890I-100J173D01*
G02X508780Y287356I5255J-8685D01*
G02X515570Y284751I0J-10152D01*
G03X515574Y284747I143J139D01*
G02X518932Y277204I-6793J-7543D01*
G01Y277202D01*
G02X518150Y273296I-10152J1D01*
G03X518241Y273042I184J-77D01*
G02X518979Y272588I-3083J-5838D01*
G03X519211I116J163D01*
G02X526853I3821J-5384D01*
G03X527085I116J163D01*
G02X534727I3821J-5384D01*
G03X534959I116J163D01*
G02X542601I3821J-5384D01*
G03X542833I116J163D01*
G02X550475I3821J-5384D01*
G03X550707I116J163D01*
G02X558349I3821J-5384D01*
G03X558581I116J163D01*
G02X562397Y273806I3821J-5384D01*
G01X562449D01*
X562538Y273855D01*
X562775Y274228D01*
X562781Y274329D01*
X562759Y274376D01*
G02X562128Y277204I6022J2828D01*
G02X568780Y270552I6652J0D01*
G01X568703D01*
X568613Y270504D01*
X568375Y270132D01*
X568368Y270031D01*
X568390Y269984D01*
G02X569004Y267204I-5988J-2780D01*
G02X562402Y260602I-6602J0D01*
G02X558581Y261820I0J6602D01*
G03X558349I-116J-163D01*
G02X550707I-3821J5384D01*
G03X550475I-116J-163D01*
G02X542833I-3821J5384D01*
G03X542601I-116J-163D01*
G02X534959I-3821J5384D01*
G03X534727I-116J-163D01*
G02X527085I-3821J5384D01*
G03X526853I-116J-163D01*
G02X519211I-3821J5384D01*
G03X518979I-116J-163D01*
G02X515158Y260602I-3821J5384D01*
G02X508564Y266870I0J6602D01*
G03X508373Y267060I-200J-10D01*
G02X501564Y270063I407J10144D01*
G01X501536Y270092D01*
X501463Y270122D01*
X501097D01*
X501024Y270092D01*
X500996Y270063D01*
G02X493780Y267052I-7216J7141D01*
G02Y287356I0J10152D01*
G02X500996Y284345I0J-10152D01*
G01X501024Y284316D01*
X501097Y284286D01*
X501463D01*
X501536Y284316D01*
X501564Y284345D01*
G02X503520Y285887I7216J-7141D01*
G37*
G36*
G01X1008047Y202399D02*
X1015827Y210179D01*
X1037807D01*
X1040500Y207486D01*
Y188243D01*
X1040530Y188169D01*
X1040559Y188141D01*
X1040641Y188059D01*
G03X1040783Y188000I142J141D01*
G01X1042917D01*
G02X1043059Y187941I0J-200D01*
G01X1043397Y187603D01*
G02X1043456Y187461I-141J-142D01*
G01Y178267D01*
G02X1043397Y178125I-200J0D01*
G01X1042984Y177712D01*
G03X1042925Y177570I141J-142D01*
G01Y173647D01*
X1042719Y173441D01*
X1036258D01*
G03X1036116Y173382I0J-200D01*
G01X1034820Y172086D01*
G03X1034761Y171944I141J-142D01*
G01Y152262D01*
G03X1034961Y152062I200J0D01*
G01X1040505D01*
G02X1040647Y152003I0J-200D01*
G01X1040868Y151782D01*
G02X1040927Y151640I-141J-142D01*
G01Y145006D01*
G02X1040868Y144864I-200J0D01*
G01X1040031Y144027D01*
G03X1039972Y143885I141J-142D01*
G01Y140180D01*
G02X1039913Y140038I-200J0D01*
G01X1033575Y133700D01*
G02X1033433Y133641I-142J141D01*
G01X1021973D01*
G02X1021831Y133700I0J200D01*
G01X1016059Y139472D01*
X1016058Y139473D01*
X1013824Y141707D01*
Y177480D01*
X1008106Y183198D01*
G02X1008047Y183340I141J142D01*
G01Y202399D01*
G37*
G54D113*
X754000Y353500D03*
Y356957D03*
G54D119*
X1084740Y108000D03*
X1068900Y110000D03*
G54D110*
X48780Y339724D03*
G54D112*
X161400Y323200D03*
X748075Y366500D03*
X724000Y294500D03*
X518575Y295500D03*
G54D121*
X1240158Y57480D03*
G54D118*
X268000Y220315D03*
X312500D03*
X357000D03*
X428500D03*
X472500D03*
X516500D03*
X578500D03*
X622500D03*
X666500D03*
X735981D03*
X779981D03*
X823981D03*
G54D115*
X185224Y539000D03*
X233224D03*
X281224D03*
X342704D03*
X390704D03*
X438704D03*
X500185D03*
X548185D03*
X596185D03*
X657666D03*
X705666D03*
X753666D03*
G54D111*
X178819Y277204D03*
X268819D03*
X426299D03*
X583780D03*
X741261D03*
G54D114*
X193819Y477204D03*
X351299D03*
X508780D03*
X666261D03*
G54D120*
X1226024Y174429D03*
Y399429D03*
G54D117*
X249252Y129685D03*
X529252D03*
X665059Y149408D03*
G54D116*
X201000Y20500D03*
%LPD*%
G75*
G36*
G01X180058Y519500D02*
X184456D01*
G02X184598Y519441I0J-200D01*
G01X184980Y519059D01*
G02X185039Y518917I-141J-142D01*
G01Y497583D01*
G02X184980Y497441I-200J0D01*
G01X184598Y497059D01*
G02X184456Y497000I-142J141D01*
G01X180058D01*
X179558Y497500D01*
Y519000D01*
X180058Y519500D01*
G37*
G36*
G01X238768Y248620D02*
X244589D01*
X246879D01*
X247159Y248340D01*
Y234710D01*
X246679Y234230D01*
X239594D01*
X239535Y234289D01*
Y241137D01*
X238676Y241996D01*
Y248528D01*
X238768Y248620D01*
G37*
G36*
G01X228058Y519500D02*
X232456D01*
G02X232598Y519441I0J-200D01*
G01X232980Y519059D01*
G02X233039Y518917I-141J-142D01*
G01Y497583D01*
G02X232980Y497441I-200J0D01*
G01X232598Y497059D01*
G02X232456Y497000I-142J141D01*
G01X228058D01*
X227558Y497500D01*
Y519000D01*
X228058Y519500D01*
G37*
G36*
G01X291660Y207060D02*
X297640D01*
X298080Y206620D01*
Y194350D01*
X297710Y193980D01*
X291610D01*
X291470Y194120D01*
Y206870D01*
X291660Y207060D01*
G37*
G36*
G01X276058Y519500D02*
X280456D01*
G02X280598Y519441I0J-200D01*
G01X280980Y519059D01*
G02X281039Y518917I-141J-142D01*
G01Y497583D01*
G02X280980Y497441I-200J0D01*
G01X280598Y497059D01*
G02X280456Y497000I-142J141D01*
G01X276058D01*
X275558Y497500D01*
Y519000D01*
X276058Y519500D01*
G37*
G36*
G01X313160Y207060D02*
X319140D01*
X319580Y206620D01*
Y194350D01*
X319210Y193980D01*
X313110D01*
X312970Y194120D01*
Y206870D01*
X313160Y207060D01*
G37*
G36*
G01X334660D02*
X340640D01*
X341080Y206620D01*
Y194350D01*
X340710Y193980D01*
X334610D01*
X334470Y194120D01*
Y206870D01*
X334660Y207060D01*
G37*
G36*
G01X356160D02*
X362140D01*
X362580Y206620D01*
Y194350D01*
X362210Y193980D01*
X356110D01*
X355970Y194120D01*
Y206870D01*
X356160Y207060D01*
G37*
G36*
G01X337538Y519500D02*
X341936D01*
G02X342078Y519441I0J-200D01*
G01X342460Y519059D01*
G02X342519Y518917I-141J-142D01*
G01Y497583D01*
G02X342460Y497441I-200J0D01*
G01X342078Y497059D01*
G02X341936Y497000I-142J141D01*
G01X337538D01*
X337038Y497500D01*
Y519000D01*
X337538Y519500D01*
G37*
G36*
G01X377660Y207060D02*
X383640D01*
X384080Y206620D01*
Y194350D01*
X383710Y193980D01*
X377610D01*
X377470Y194120D01*
Y206870D01*
X377660Y207060D01*
G37*
G36*
G01X385538Y519500D02*
X389936D01*
G02X390078Y519441I0J-200D01*
G01X390460Y519059D01*
G02X390519Y518917I-141J-142D01*
G01Y497583D01*
G02X390460Y497441I-200J0D01*
G01X390078Y497059D01*
G02X389936Y497000I-142J141D01*
G01X385538D01*
X385038Y497500D01*
Y519000D01*
X385538Y519500D01*
G37*
G36*
G01X399160Y207060D02*
X405140D01*
X405580Y206620D01*
Y194350D01*
X405210Y193980D01*
X399110D01*
X398970Y194120D01*
Y206870D01*
X399160Y207060D01*
G37*
G36*
G01X394729Y248120D02*
X400589D01*
X402879D01*
X403159Y247840D01*
Y234210D01*
X402679Y233730D01*
X395592D01*
X395539Y233783D01*
Y240633D01*
X394675Y241497D01*
Y248066D01*
X394729Y248120D01*
G37*
G36*
G01X403480Y279000D02*
X404674Y277806D01*
G03X404647Y277211I6625J-599D01*
G01Y277204D01*
G03X411299Y270552I6652J0D01*
G03X415991Y272489I0J6651D01*
G01X420480Y268000D01*
Y262000D01*
X418480Y260000D01*
X410580D01*
X409680Y260900D01*
Y266549D01*
X409025Y267204D01*
G03X404921Y271308I-4104J0D01*
G03X404494Y271286I-3J-4104D01*
G01X402740Y273040D01*
X401060D01*
X400500Y273600D01*
Y278900D01*
X400600Y279000D01*
X403480D01*
G37*
G36*
G01X420660Y207060D02*
X426640D01*
X427080Y206620D01*
Y194350D01*
X426710Y193980D01*
X420610D01*
X420470Y194120D01*
Y206870D01*
X420660Y207060D01*
G37*
G36*
G01X433538Y519500D02*
X437936D01*
G02X438078Y519441I0J-200D01*
G01X438460Y519059D01*
G02X438519Y518917I-141J-142D01*
G01Y497583D01*
G02X438460Y497441I-200J0D01*
G01X438078Y497059D01*
G02X437936Y497000I-142J141D01*
G01X433538D01*
X433038Y497500D01*
Y519000D01*
X433538Y519500D01*
G37*
G36*
G01X495019D02*
X499417D01*
G02X499559Y519441I0J-200D01*
G01X499941Y519059D01*
G02X500000Y518917I-141J-142D01*
G01Y497583D01*
G02X499941Y497441I-200J0D01*
G01X499559Y497059D01*
G02X499417Y497000I-142J141D01*
G01X495019D01*
X494519Y497500D01*
Y519000D01*
X495019Y519500D01*
G37*
G36*
G01X548241Y249120D02*
X554089D01*
X556379D01*
X556659Y248840D01*
Y235210D01*
X556179Y234730D01*
X549107D01*
X549040Y234797D01*
Y241633D01*
X548174Y242499D01*
Y249053D01*
X548241Y249120D01*
G37*
G36*
G01X558081Y279000D02*
X560961D01*
X562155Y277806D01*
G03X562128Y277211I6625J-599D01*
G01Y277204D01*
G03X568780Y270552I6652J0D01*
G03X573472Y272489I0J6651D01*
G01X577961Y268000D01*
Y262000D01*
X575961Y260000D01*
X568061D01*
X567161Y260900D01*
Y266549D01*
X566506Y267204D01*
G03X562402Y271308I-4104J0D01*
G01X562397D01*
G03X561975Y271286I2J-4104D01*
G01X560221Y273040D01*
X558541D01*
X557981Y273600D01*
Y278900D01*
X558081Y279000D01*
G37*
G36*
G01X543019Y519500D02*
X547417D01*
G02X547559Y519441I0J-200D01*
G01X547941Y519059D01*
G02X548000Y518917I-141J-142D01*
G01Y497583D01*
G02X547941Y497441I-200J0D01*
G01X547559Y497059D01*
G02X547417Y497000I-142J141D01*
G01X543019D01*
X542519Y497500D01*
Y519000D01*
X543019Y519500D01*
G37*
G36*
G01X591019D02*
X595417D01*
G02X595559Y519441I0J-200D01*
G01X595941Y519059D01*
G02X596000Y518917I-141J-142D01*
G01Y497583D01*
G02X595941Y497441I-200J0D01*
G01X595559Y497059D01*
G02X595417Y497000I-142J141D01*
G01X591019D01*
X590519Y497500D01*
Y519000D01*
X591019Y519500D01*
G37*
G36*
G01X599160Y206560D02*
X605140D01*
X605580Y206120D01*
Y193850D01*
X605210Y193480D01*
X599110D01*
X598970Y193620D01*
Y206370D01*
X599160Y206560D01*
G37*
G36*
G01X620660D02*
X626640D01*
X627080Y206120D01*
Y193850D01*
X626710Y193480D01*
X620610D01*
X620470Y193620D01*
Y206370D01*
X620660Y206560D01*
G37*
G36*
G01X642160D02*
X648140D01*
X648580Y206120D01*
Y193850D01*
X648210Y193480D01*
X642110D01*
X641970Y193620D01*
Y206370D01*
X642160Y206560D01*
G37*
G36*
G01X652500Y519500D02*
X656898D01*
G02X657040Y519441I0J-200D01*
G01X657422Y519059D01*
G02X657481Y518917I-141J-142D01*
G01Y497583D01*
G02X657422Y497441I-200J0D01*
G01X657040Y497059D01*
G02X656898Y497000I-142J141D01*
G01X652500D01*
X652000Y497500D01*
Y519000D01*
X652500Y519500D01*
G37*
G36*
G01X663660Y206560D02*
X669640D01*
X670080Y206120D01*
Y193850D01*
X669710Y193480D01*
X663610D01*
X663470Y193620D01*
Y206370D01*
X663660Y206560D01*
G37*
G36*
G01X685160D02*
X691140D01*
X691580Y206120D01*
Y193850D01*
X691210Y193480D01*
X685110D01*
X684970Y193620D01*
Y206370D01*
X685160Y206560D01*
G37*
G36*
G01X706650D02*
X712630D01*
X713070Y206120D01*
Y193850D01*
X712700Y193480D01*
X706600D01*
X706460Y193620D01*
Y206370D01*
X706650Y206560D01*
G37*
G36*
G01X705726Y249120D02*
X711570D01*
X713860D01*
X714140Y248840D01*
Y235210D01*
X713660Y234730D01*
X706578D01*
X706521Y234787D01*
Y241627D01*
X705653Y242495D01*
Y249047D01*
X705726Y249120D01*
G37*
G36*
G01X715562Y279000D02*
X718442D01*
X719636Y277806D01*
G03X719609Y277211I6625J-599D01*
G01Y277204D01*
G03X726261Y270552I6652J0D01*
G03X730953Y272489I0J6651D01*
G01X735442Y268000D01*
Y262000D01*
X733442Y260000D01*
X725542D01*
X724642Y260900D01*
Y266549D01*
X723987Y267204D01*
G03X719883Y271308I-4104J0D01*
G01X719878D01*
G03X719456Y271286I2J-4104D01*
G01X717702Y273040D01*
X716022D01*
X715462Y273600D01*
Y278900D01*
X715562Y279000D01*
G37*
G36*
G01X700500Y519500D02*
X704898D01*
G02X705040Y519441I0J-200D01*
G01X705422Y519059D01*
G02X705481Y518917I-141J-142D01*
G01Y497583D01*
G02X705422Y497441I-200J0D01*
G01X705040Y497059D01*
G02X704898Y497000I-142J141D01*
G01X700500D01*
X700000Y497500D01*
Y519000D01*
X700500Y519500D01*
G37*
G36*
G01X728150Y206560D02*
X734130D01*
X734570Y206120D01*
Y193850D01*
X734200Y193480D01*
X728100D01*
X727960Y193620D01*
Y206370D01*
X728150Y206560D01*
G37*
G36*
G01X748500Y519500D02*
X752898D01*
G02X753040Y519441I0J-200D01*
G01X753422Y519059D01*
G02X753481Y518917I-141J-142D01*
G01Y497583D01*
G02X753422Y497441I-200J0D01*
G01X753040Y497059D01*
G02X752898Y497000I-142J141D01*
G01X748500D01*
X748000Y497500D01*
Y519000D01*
X748500Y519500D01*
G37*
G36*
G01X1027110Y150801D02*
X1028248D01*
X1028393Y150656D01*
Y140596D01*
X1028087Y140290D01*
X1021993D01*
X1021745Y140538D01*
Y145095D01*
Y146497D01*
X1022874Y147626D01*
X1026669D01*
X1027021Y147978D01*
Y150712D01*
X1027110Y150801D01*
G37*
G36*
G01X1023295Y177505D02*
X1025600Y175200D01*
X1026500Y174300D01*
Y173100D01*
X1026400Y173000D01*
X1023700D01*
X1023600Y173100D01*
X1015547Y181153D01*
Y186364D01*
Y198504D01*
Y198933D01*
X1018590Y201976D01*
X1022991D01*
X1023019Y201948D01*
Y177781D01*
X1023295Y177505D01*
G37*
G36*
G01X1026134Y191562D02*
X1030423D01*
X1030501Y191484D01*
Y180038D01*
X1028411Y177948D01*
Y174880D01*
X1028295Y174764D01*
X1027159D01*
X1027071Y174852D01*
Y184778D01*
X1025956Y185893D01*
Y191384D01*
X1026134Y191562D01*
G37*
G36*
G01X1033507Y179410D02*
X1034899Y178018D01*
Y174673D01*
X1034994Y174578D01*
X1036144D01*
X1036225Y174659D01*
Y189200D01*
X1039693Y192668D01*
Y198878D01*
X1039052Y199519D01*
X1036612Y201959D01*
X1026081D01*
X1026066Y201944D01*
Y196580D01*
X1026109Y196537D01*
X1031247D01*
X1033484Y194300D01*
X1033507Y194277D01*
Y179410D01*
G37*
G54D100*
X1226024Y174429D03*
Y399429D03*
G54D101*
G01X153180Y215785D02*
Y213650D01*
X153480Y213350D01*
G01X138425Y232208D02*
X139018Y231615D01*
G01X138425Y232208D02*
Y243768D01*
X144853Y250196D01*
X157926D01*
X158982Y249140D01*
G01X181750Y234630D02*
X177540D01*
X173047Y230137D01*
X169612D01*
G01X178265Y247712D02*
Y242330D01*
G01Y238330D02*
X172041Y232106D01*
X169612D01*
G01X178265Y242330D02*
Y238330D01*
G01X704610Y36695D02*
Y38720D01*
X703740Y39590D01*
Y41000D01*
G01D02*
Y43363D01*
G01X710000Y46425D02*
Y42075D01*
G01X694425Y32000D02*
X694460Y32035D01*
Y36695D01*
G01D02*
Y37520D01*
X696240Y39300D01*
X698420D01*
X699016Y39896D01*
Y41591D01*
G01X694425Y32000D02*
Y29500D01*
G01D02*
Y27000D01*
G01X703740Y51237D02*
Y54118D01*
G01D02*
X706000Y56378D01*
Y56425D01*
G01X1019040Y157310D02*
X1019710Y157980D01*
X1023060D01*
X1023194Y157846D01*
X1025168D01*
G01X1019030Y160330D02*
X1019880Y159480D01*
X1023100D01*
X1023434Y159814D01*
X1025168D01*
G01Y155877D02*
X1022168D01*
G01X1017909Y151424D02*
X1018600Y152115D01*
X1023281D01*
X1023456Y151940D01*
X1025068D01*
G01X1017837Y154280D02*
X1018442Y153675D01*
X1023175D01*
X1023409Y153909D01*
X1025168D01*
G01X1041500Y185925D02*
X1041507Y185918D01*
Y181500D01*
X1041867Y181140D01*
Y178636D01*
X1041507Y178276D01*
Y176153D01*
G01X1025168Y161783D02*
X1022168D01*
G01X1127148Y180279D02*
Y182227D01*
X1127239Y182318D01*
Y184733D01*
X1126640Y185332D01*
Y192034D01*
X1125918Y192756D01*
G01X1129118Y180279D02*
Y182103D01*
X1128920Y182301D01*
Y185174D01*
X1128140Y185954D01*
Y191828D01*
X1129068Y192756D01*
G01X1125918D02*
Y195418D01*
G01X1129068Y192756D02*
Y195500D01*
G01X1114806Y231741D02*
X1117206D01*
G01X1114890Y224241D02*
X1117290D01*
G01X1108506Y231741D02*
X1106106D01*
G01X1130368Y228060D02*
X1125568D01*
X1121568Y232060D01*
G01X1111656Y231741D02*
Y229809D01*
X1112656Y228809D01*
X1118317D01*
X1121568Y232060D01*
G01X1130368Y228060D02*
X1136600D01*
G01X1111740Y224241D02*
Y226209D01*
X1112840Y227309D01*
X1118319D01*
X1121568Y224060D01*
G01X1135000Y220600D02*
X1131540Y224060D01*
X1121568D01*
G01X1140336Y183560D02*
X1140928Y182968D01*
Y180279D01*
G01X1143490Y183560D02*
X1142898Y182968D01*
Y180279D01*
G01X1166000Y148240D02*
X1181750D01*
X1183561Y150051D01*
Y156451D01*
G01X1176593Y307942D02*
X1177651D01*
X1179651Y309942D01*
G01X1182709Y307942D02*
X1181651D01*
X1179651Y305942D01*
G01X1176682Y450442D02*
X1176683Y450441D01*
X1177876D01*
X1179877Y452442D01*
G01Y448442D02*
X1181877Y450442D01*
X1182798D01*
G54D102*
G01X1022000Y171200D02*
X1022425Y171625D01*
X1025168D01*
G01X1019700Y166600D02*
X1021100D01*
X1024157Y169657D01*
X1025168D01*
G54D103*
G01X1147618Y169649D02*
X1149185D01*
X1152500Y172964D01*
G54D10*
G01X645575Y37000D02*
X647975D01*
G01X684525Y36500D02*
X686925D01*
G01Y32500D02*
X684525D01*
G01X706000Y59575D02*
Y61975D01*
G01X797854Y262239D02*
Y259539D01*
G01X809500Y262130D02*
Y259430D01*
G01X830630Y329000D02*
X827500D01*
G01X1175075Y111500D02*
X1177475D01*
G01X1176400Y105500D02*
X1179500D01*
X3005Y19808D03*
Y34808D03*
Y59808D03*
X7595Y128373D03*
X3005Y145238D03*
Y165238D03*
Y185238D03*
Y205238D03*
Y225238D03*
Y245238D03*
Y265238D03*
Y285238D03*
Y305238D03*
Y325238D03*
Y345238D03*
Y365238D03*
Y385238D03*
Y405238D03*
Y425238D03*
Y445238D03*
X3023Y524312D03*
Y549312D03*
X4540Y566003D03*
X34582Y3004D03*
X14811Y3732D03*
X12767Y72072D03*
X27271Y127298D03*
X19558Y454589D03*
X9913Y510026D03*
X20498Y575739D03*
X54582Y3004D03*
X63436Y353962D03*
X39549Y454916D03*
X40498Y575739D03*
X60498D03*
X94582Y3004D03*
X74582D03*
X80498Y575739D03*
X114582Y3004D03*
X108600Y258560D03*
X111600D03*
X108600Y261560D03*
X111600D03*
X108600Y255560D03*
X111600D03*
X123000Y414500D03*
X119500D03*
Y411500D03*
X123000D03*
X119500Y408500D03*
X123000D03*
X119500Y417500D03*
X123000D03*
X119500Y420500D03*
X123000D03*
X115700Y420600D03*
Y417600D03*
Y408600D03*
Y411600D03*
Y414600D03*
X123000Y426600D03*
X119500D03*
X123000Y423600D03*
X119500D03*
X115700Y423700D03*
Y426700D03*
X100498Y575739D03*
X120498D03*
X154582Y3004D03*
X134582D03*
X153480Y213350D03*
X150634Y219063D03*
X155140Y240230D03*
X154840Y244730D03*
X155034Y228063D03*
Y224563D03*
X152334Y223063D03*
Y226563D03*
Y230063D03*
X155034Y231563D03*
X140400Y258360D03*
X143400D03*
X140400Y261360D03*
X143400D03*
X140400Y255360D03*
X143400D03*
X140498Y575739D03*
X174582Y3004D03*
X172934Y219110D03*
X184349Y212651D03*
X182260Y197050D03*
X179460D03*
X176560D03*
X174660Y205850D03*
Y202650D03*
X167660Y213050D03*
X164760D03*
X167660Y209850D03*
X164760D03*
X183900Y216830D03*
X178265Y213443D03*
X175976Y218775D03*
X172712Y222263D03*
X183815Y220903D03*
X165840Y247805D03*
X169840D03*
X166068Y238749D03*
X173869Y228168D03*
X175481Y225183D03*
X160017Y237764D03*
X161400Y323200D03*
X173265Y340552D03*
X157000Y414500D03*
X160500D03*
Y417500D03*
X157000D03*
X160500Y420500D03*
X157000D03*
X160500Y411500D03*
X157000D03*
X160500Y408500D03*
X157000D03*
X164000Y414600D03*
Y417600D03*
Y420600D03*
Y411600D03*
Y408600D03*
X160300Y423600D03*
X156800D03*
X160300Y426600D03*
X156800D03*
X163800Y426700D03*
Y423700D03*
X183539Y518000D03*
X180539Y498000D03*
X183539D03*
X168939D03*
X171939D03*
Y518000D03*
X180539D03*
X168939D03*
X214582Y3004D03*
X194582D03*
X194160Y205200D03*
Y208200D03*
X200160Y205200D03*
Y208200D03*
X197160Y205200D03*
Y208200D03*
X185260Y205350D03*
Y208350D03*
X189760Y242100D03*
Y245100D03*
X192760Y242100D03*
Y245100D03*
X195760Y242100D03*
Y245100D03*
X198760Y242100D03*
Y245100D03*
X201760Y242100D03*
Y245100D03*
X208071Y305975D03*
X203575Y297500D03*
X212925Y315500D03*
X234582Y3004D03*
X246000Y238500D03*
X242500Y243000D03*
Y247500D03*
X218500Y305000D03*
X226975D03*
X235975D03*
X239567Y305975D03*
X218500Y309500D03*
X226975D03*
X235975D03*
X230425Y313605D03*
X221425Y313000D03*
X223819Y445025D03*
X231539Y518000D03*
X228539Y498000D03*
X231539D03*
X216939D03*
X219939D03*
Y518000D03*
X228539D03*
X216939D03*
X254582Y3004D03*
X246000Y235500D03*
X247441Y305975D03*
X264939Y498000D03*
X267939D03*
Y518000D03*
X264939D03*
X294582Y3004D03*
X274582D03*
X297000Y206000D03*
Y203500D03*
Y198500D03*
Y196000D03*
X283000Y203500D03*
Y198500D03*
Y196000D03*
Y206000D03*
X285219Y279078D03*
X281219D03*
X277219D03*
X285219Y275078D03*
X281219D03*
X277219D03*
X285219Y271078D03*
X281219D03*
X277219D03*
Y283078D03*
X281219D03*
X285219D03*
X290720Y340338D03*
X279539Y518000D03*
X276539Y498000D03*
X279539D03*
X276539Y518000D03*
X314582Y3004D03*
X318500Y206000D03*
Y203500D03*
Y198500D03*
Y196000D03*
X326000Y203500D03*
Y198500D03*
Y196000D03*
Y206000D03*
X304500Y203500D03*
Y198500D03*
Y196000D03*
Y206000D03*
X313571Y340552D03*
X326419Y498000D03*
X329419D03*
Y518000D03*
X326419D03*
X354582Y3004D03*
X334582D03*
X340000Y206000D03*
Y203500D03*
Y198500D03*
Y196000D03*
X361500Y206000D03*
Y203500D03*
Y198500D03*
Y196000D03*
X347500Y203500D03*
Y198500D03*
Y196000D03*
Y206000D03*
X361000Y305975D03*
X341019Y518000D03*
X338019Y498000D03*
X341019D03*
X338019Y518000D03*
X374582Y3004D03*
X383000Y206000D03*
Y203500D03*
Y198500D03*
Y196000D03*
X390500Y203500D03*
Y198500D03*
Y196000D03*
Y206000D03*
X369000Y203500D03*
Y198500D03*
Y196000D03*
Y206000D03*
X375475Y305000D03*
X383975D03*
X365551Y305975D03*
X375500Y309500D03*
X383975D03*
X382963Y316400D03*
Y313750D03*
X381299Y445025D03*
X389019Y518000D03*
X386019Y498000D03*
X389019D03*
X374419D03*
X377419D03*
Y518000D03*
X386019D03*
X374419D03*
X414582Y3004D03*
X394582D03*
X404500Y206000D03*
Y203500D03*
Y198500D03*
Y196000D03*
X412000Y203500D03*
Y198500D03*
Y196000D03*
Y206000D03*
X402000Y235000D03*
Y238000D03*
X398500Y247000D03*
Y242500D03*
X393000Y305000D03*
X397047Y305975D03*
X404921D03*
X392975Y309500D03*
X434582Y3004D03*
X426000Y206000D03*
Y203500D03*
Y198500D03*
Y196000D03*
X442499Y279186D03*
X438499D03*
X434499D03*
X442499Y275186D03*
X438499D03*
X434499D03*
X442499Y271186D03*
X438499D03*
X434499D03*
Y283186D03*
X438499D03*
X442499D03*
X447255Y340339D03*
X430019Y444260D03*
X432019Y452025D03*
X437019Y518000D03*
X434019Y498000D03*
X437019D03*
X422419D03*
X425419D03*
Y518000D03*
X434019D03*
X422419D03*
X474582Y3004D03*
X454582D03*
X473095Y340339D03*
X494582Y3004D03*
X498500Y498000D03*
X495500D03*
X498500Y518000D03*
X483900Y498000D03*
X486900D03*
Y518000D03*
X495500D03*
X483900D03*
X534582Y3004D03*
X514582D03*
X533475Y305500D03*
X523032Y305975D03*
X518575Y295500D03*
X533475Y310500D03*
X539619Y316400D03*
Y313400D03*
X538780Y445025D03*
X531900Y498000D03*
X534900D03*
Y518000D03*
X531900D03*
X554582Y3004D03*
X555500Y239000D03*
Y236000D03*
X552000Y243500D03*
Y247000D03*
X542475Y305500D03*
X551475D03*
X554528Y305975D03*
X562402D03*
X542475Y310500D03*
X551475D03*
X545063Y340339D03*
X549500Y445024D03*
X562000Y442000D03*
X564500D03*
X546500Y498000D03*
X543500D03*
X546500Y518000D03*
X543500D03*
X594582Y3004D03*
X574582D03*
X590500Y203000D03*
Y198000D03*
Y195500D03*
Y205500D03*
X587500Y444260D03*
X589500Y446500D03*
X594500Y498000D03*
X591500D03*
X594500Y518000D03*
X582900D03*
Y498000D03*
X579900D03*
X591500Y518000D03*
X579900D03*
X614582Y3004D03*
X604500Y205500D03*
Y203000D03*
Y198000D03*
Y195500D03*
X626000Y205500D03*
Y203000D03*
Y198000D03*
Y195500D03*
X612000Y203000D03*
Y198000D03*
Y195500D03*
Y205500D03*
X654582Y3004D03*
X634582D03*
X647975Y37000D03*
X640900Y42300D03*
X647999Y33000D03*
X660200Y56800D03*
X655300D03*
X652300D03*
X638200Y44000D03*
Y46500D03*
X641100Y48100D03*
X647500Y205500D03*
Y203000D03*
Y198000D03*
Y195500D03*
X655000Y203000D03*
Y198000D03*
Y195500D03*
Y205500D03*
X633500Y203000D03*
Y198000D03*
Y195500D03*
Y205500D03*
X655981Y518000D03*
Y498000D03*
X652981D03*
X644381Y518000D03*
Y498000D03*
X641381D03*
X652981Y518000D03*
X641381D03*
X674582Y3004D03*
X684525Y32500D03*
Y36500D03*
X690075Y39500D03*
X683600Y56800D03*
X679000D03*
X676000D03*
X686500D03*
X671100D03*
X668100D03*
X663200D03*
X669000Y205500D03*
Y203000D03*
Y198000D03*
Y195500D03*
X676500D03*
Y198000D03*
Y203000D03*
Y205500D03*
X680513Y305975D03*
X676075Y299600D03*
X680400Y310500D03*
X714582Y3004D03*
X694582D03*
X699500Y34500D03*
X703740Y41000D03*
X707000Y32000D03*
X694425Y29500D03*
X696900Y53300D03*
X694200D03*
X691400D03*
X689900Y56600D03*
X693000D03*
X696100Y56700D03*
X706000Y61975D03*
X703740Y54118D03*
X690500Y205500D03*
Y203000D03*
Y198000D03*
Y195500D03*
X711990D03*
Y198000D03*
Y203000D03*
Y205500D03*
X697990Y195500D03*
Y198000D03*
Y203000D03*
Y205500D03*
X709500Y247000D03*
X709481Y243500D03*
X712981Y236000D03*
Y239000D03*
X716100Y255987D03*
X700040Y258960D03*
X712009Y305975D03*
X708956Y305500D03*
X690956D03*
X700000D03*
X694406Y295500D03*
X690956Y310500D03*
X699956D03*
X708956D03*
X697100Y313400D03*
X704400Y358600D03*
X702200Y356000D03*
X697900Y352500D03*
X707750Y358750D03*
X696261Y445024D03*
X703981Y518000D03*
Y498000D03*
X700981D03*
X692381Y518000D03*
Y498000D03*
X689381D03*
X700981Y518000D03*
X689381D03*
X734582Y3004D03*
X747160Y30000D03*
Y38500D03*
Y64000D03*
Y47000D03*
Y55500D03*
X733490Y195500D03*
Y198000D03*
Y203000D03*
Y205500D03*
X719490Y195500D03*
Y198000D03*
Y203000D03*
Y205500D03*
X719883Y305975D03*
X724000Y294500D03*
X732100Y332400D03*
X742500Y328500D03*
Y324500D03*
Y334500D03*
X735075Y326000D03*
Y336000D03*
X731925D03*
X732000Y326000D03*
X742500Y361500D03*
X742000Y341500D03*
X742500Y347700D03*
Y353200D03*
X740381Y518000D03*
Y498000D03*
X737381D03*
Y518000D03*
X774582Y3004D03*
X754582D03*
X761560Y38500D03*
X758760D03*
X756160D03*
X761560Y30000D03*
X758760D03*
X756160D03*
X758900Y27400D03*
X750300Y27200D03*
X752560Y30100D03*
X749760D03*
X752560Y38600D03*
X749760D03*
X761560Y55500D03*
X758760D03*
X756160D03*
X761560Y47000D03*
X758760D03*
X756160D03*
X761560Y64000D03*
X758760D03*
X756160D03*
X752560Y64100D03*
X749760D03*
X752560Y47100D03*
X749760D03*
X752560Y55600D03*
X749760D03*
X754000Y353500D03*
Y356957D03*
X748075Y366500D03*
X748981Y498000D03*
X751981D03*
Y518000D03*
X748981D03*
X794582Y3004D03*
X797854Y259539D03*
X803900Y279425D03*
X803500Y259525D03*
X784855Y265184D03*
X790000Y259612D03*
X794900Y265979D03*
X806000Y265075D03*
X806500Y285500D03*
X786500Y336484D03*
X800575Y338000D03*
X779100Y326820D03*
X798400Y323900D03*
X786500Y316700D03*
X793800Y323880D03*
X781500Y362700D03*
X803000Y357000D03*
Y346500D03*
X802975Y362000D03*
X805323Y408150D03*
Y405150D03*
X799323D03*
Y408150D03*
X802323Y405150D03*
Y408150D03*
X796600Y408097D03*
Y405097D03*
X802323Y416916D03*
X799323D03*
X805323D03*
X802323Y413916D03*
X799323D03*
X805323D03*
Y411150D03*
X799323D03*
X802323D03*
X796600Y411097D03*
Y413863D03*
Y416863D03*
X799655Y474684D03*
Y480503D03*
Y477684D03*
X802655Y474684D03*
Y480503D03*
Y477684D03*
X805655Y474684D03*
Y480503D03*
Y477684D03*
X802655Y483503D03*
X805709Y486332D03*
X805655Y483503D03*
X796655Y474684D03*
Y480503D03*
Y477684D03*
X796709Y486332D03*
X796655Y483503D03*
X799709Y486332D03*
X799655Y483503D03*
X802709Y486332D03*
X834582Y3004D03*
X814582D03*
X809500Y259430D03*
X808500Y272925D03*
X831000Y260500D03*
X836000D03*
X826000Y260525D03*
X831000Y270500D03*
X808500Y276075D03*
X836000Y270500D03*
X826000Y270525D03*
X821000D03*
X814500Y293000D03*
X819500Y329000D03*
X827500D03*
X811500D03*
X815500D03*
X823500D03*
X808425Y334000D03*
X825941Y339560D03*
X813975Y362000D03*
Y357000D03*
X835610Y355590D03*
X829500Y354925D03*
X827000Y360475D03*
X811575Y344000D03*
X808425D03*
X811323Y405150D03*
Y408150D03*
X808323D03*
Y405150D03*
Y416916D03*
X811323D03*
X808323Y413916D03*
X811323D03*
Y411150D03*
X808323D03*
X817153Y408096D03*
Y405096D03*
X814323Y405150D03*
Y408150D03*
Y416916D03*
X817153Y416862D03*
X814323Y413916D03*
X817153Y413862D03*
Y411096D03*
X814323Y411150D03*
X817709Y486332D03*
X817655Y483503D03*
X808655Y474684D03*
Y480503D03*
Y477684D03*
X811655Y474684D03*
Y480503D03*
Y477684D03*
X814655D03*
Y480503D03*
Y474684D03*
X808709Y486332D03*
X808655Y483503D03*
X811709Y486332D03*
X811655Y483503D03*
X814655D03*
X814709Y486332D03*
X817655Y474684D03*
Y480503D03*
Y477684D03*
X854582Y3004D03*
X849490Y196000D03*
Y198500D03*
Y203500D03*
Y206000D03*
X863600Y208900D03*
X841000Y260525D03*
X846000D03*
X851000D03*
X856000D03*
X841000Y270500D03*
X846000Y270525D03*
X851000D03*
X856000D03*
X850750Y250750D03*
X848075Y306500D03*
X853000Y303500D03*
X861600Y304600D03*
X837575Y321000D03*
X865000Y313200D03*
X844760Y336077D03*
X839692Y329592D03*
X854825Y330925D03*
X850500Y360075D03*
Y366000D03*
X847500D03*
X856500D03*
X859500D03*
X865500D03*
X850500Y356925D03*
X864500Y358500D03*
X850390Y385878D03*
X847390D03*
X859253D03*
X856253D03*
X865542Y385771D03*
X859342Y413916D03*
X856342D03*
X865342D03*
X862342D03*
Y411150D03*
X865342D03*
X856342D03*
X859342D03*
X853619Y411097D03*
Y413863D03*
Y416863D03*
X862342Y408150D03*
Y405150D03*
X865342Y408150D03*
Y405150D03*
X856342D03*
Y408150D03*
X859342Y405150D03*
Y408150D03*
X853619Y408097D03*
Y405097D03*
X859342Y416916D03*
X856342D03*
X865342D03*
X862342D03*
X856257Y474684D03*
Y480503D03*
Y477684D03*
X859257Y474684D03*
Y480503D03*
Y477684D03*
X862257Y474684D03*
Y480503D03*
Y477684D03*
X859257Y483503D03*
X862311Y486332D03*
X862257Y483503D03*
X853257Y474684D03*
Y480503D03*
Y477684D03*
X853311Y486332D03*
X853257Y483503D03*
X856311Y486332D03*
X856257Y483503D03*
X859311Y486332D03*
X865311D03*
X865257Y483503D03*
Y474684D03*
Y480503D03*
Y477684D03*
X854082Y505410D03*
X848263D03*
X851082D03*
X854082Y508410D03*
X848263D03*
X851082D03*
X854082Y511410D03*
X848263D03*
X851082D03*
X854082Y514410D03*
X848263D03*
X851082D03*
X845263Y508410D03*
X842434Y511464D03*
X845263Y511410D03*
X842434Y514464D03*
X845263Y514410D03*
X854082Y502410D03*
X848263D03*
X851082D03*
X842434Y502464D03*
X845263Y502410D03*
X842434Y505464D03*
X845263Y505410D03*
X842434Y508464D03*
Y523464D03*
X845263Y523410D03*
X854082Y517410D03*
X848263D03*
X851082D03*
Y520410D03*
X848263D03*
X854082D03*
X842434Y517464D03*
X845263Y517410D03*
Y520410D03*
X842434Y520464D03*
X854082Y523410D03*
X848263D03*
X851082D03*
X894582Y3004D03*
X874582D03*
X868000Y271500D03*
X894500Y283475D03*
X884000D03*
X877500D03*
X893363Y298740D03*
X883000Y293925D03*
X867000Y291260D03*
X875000Y304525D03*
X888000Y283475D03*
X877500Y366000D03*
X874500D03*
X884000D03*
X887000D03*
X893500D03*
X868500D03*
X878000Y358475D03*
X883000Y358500D03*
X874000Y358475D03*
X885500Y352925D03*
X869000Y360500D03*
X893091Y385771D03*
X874405D03*
X877405D03*
X868542D03*
X884228D03*
X887228D03*
X868342Y416916D03*
X871342D03*
X868342Y413916D03*
X871342D03*
Y411150D03*
X868342D03*
X874172Y408096D03*
Y405096D03*
Y416862D03*
Y413862D03*
Y411096D03*
X871342Y405150D03*
Y408150D03*
X868342Y405150D03*
Y408150D03*
X868311Y486332D03*
X868257Y483503D03*
Y477684D03*
Y480503D03*
Y474684D03*
X871311Y486332D03*
X874311D03*
X874257Y477684D03*
Y480503D03*
Y474684D03*
X871257Y483503D03*
Y474684D03*
Y480503D03*
Y477684D03*
X874257Y483503D03*
X914582Y3004D03*
X915500Y283475D03*
X914500Y292000D03*
X905000Y283475D03*
X905941Y306500D03*
X909000Y283475D03*
X904500Y292000D03*
X912500Y327975D03*
X916260Y337077D03*
X908000Y327975D03*
X915000Y322425D03*
X912000Y332425D03*
X903500Y327975D03*
X896500Y366000D03*
X906000D03*
X903000D03*
X912500D03*
X915500D03*
X922000D03*
X901063Y352340D03*
X910992Y361075D03*
X920000Y355525D03*
X896091Y385771D03*
X912525Y385877D03*
X906662D03*
X903662D03*
X922454Y385771D03*
X915525Y385877D03*
X911776Y507184D03*
Y510184D03*
Y501184D03*
Y504184D03*
X923595Y498461D03*
X920595D03*
X920542Y504184D03*
X923542D03*
X920542Y501184D03*
X923542D03*
Y510184D03*
X920542D03*
X923542Y507184D03*
X920542D03*
Y513184D03*
X923542D03*
X911829Y498461D03*
X914829D03*
X917595D03*
X917542Y504184D03*
Y501184D03*
Y510184D03*
Y507184D03*
Y513184D03*
X914776D03*
Y507184D03*
Y510184D03*
Y501184D03*
Y504184D03*
X911776Y513184D03*
X920542Y516184D03*
X923542D03*
X917542D03*
X914776D03*
X911776D03*
X917596Y519014D03*
X914830D03*
X911830D03*
X923596D03*
X920596D03*
X934582Y3004D03*
X940575Y304000D03*
X933000Y293476D03*
X940000D03*
X947000D03*
X926000Y283475D03*
X937516Y300075D03*
X947000Y302475D03*
X933196Y309910D03*
X930500Y315460D03*
X943172Y310885D03*
X943171Y315385D03*
X925000Y366000D03*
X944000D03*
X941000D03*
X934500D03*
X950500D03*
X953500D03*
X931500D03*
X927000Y361075D03*
X941035Y344474D03*
X927000Y357925D03*
X943885Y352385D03*
X925454Y385771D03*
X944247Y385877D03*
X941247D03*
X931317Y385771D03*
X934317D03*
X950110Y385877D03*
X953110D03*
X940498Y575739D03*
X974582Y3004D03*
X954582D03*
X960498Y575739D03*
X980498D03*
X994582Y3004D03*
X1000498Y575739D03*
X1034582Y3004D03*
X1014582D03*
X1022575Y100925D03*
Y115500D03*
X1034500Y142000D03*
Y145000D03*
X1037000Y146300D03*
X1037500Y142000D03*
X1036500Y153500D03*
X1043936Y145745D03*
X1019040Y157310D03*
X1019030Y160330D03*
X1022168Y155877D03*
Y161783D03*
X1017909Y151424D03*
X1017837Y154280D03*
X1024340Y146600D03*
X1016614Y187267D03*
Y190267D03*
X1036500Y172000D03*
Y163000D03*
X1039016Y189075D03*
Y183027D03*
X1039538Y179208D03*
X1039016Y185925D03*
X1022000Y171200D03*
X1019700Y166600D03*
X1016614Y197767D03*
X1020498Y575739D03*
X1040498D03*
X1054582Y3004D03*
X1070400Y123200D03*
X1067600D03*
X1068900Y110000D03*
X1057525Y130500D03*
X1065000Y156425D03*
X1049356Y143900D03*
X1047159Y141487D03*
X1054500Y148500D03*
X1048000Y153500D03*
X1057525Y134000D03*
Y138600D03*
X1073154Y140800D03*
X1057500Y155877D03*
X1070715Y146500D03*
X1063500Y159814D03*
X1070715Y178585D03*
X1048000Y172000D03*
Y163000D03*
X1060500Y164500D03*
X1062500Y191500D03*
X1067000D03*
X1070000D03*
X1058000D03*
X1053830Y191670D03*
X1060000Y249000D03*
X1063000D03*
X1066000D03*
Y246000D03*
X1063000D03*
X1060000D03*
X1066000Y243000D03*
X1063000D03*
X1060000D03*
X1069000Y246000D03*
Y243000D03*
X1072000Y246000D03*
Y243000D03*
X1060000Y252000D03*
X1063000D03*
X1066000D03*
Y258000D03*
X1063000D03*
X1060000D03*
X1066000Y255000D03*
X1063000D03*
X1060000D03*
X1069000Y258000D03*
Y255000D03*
X1072000Y258000D03*
Y255000D03*
X1067701Y270442D03*
X1061600Y276242D03*
X1060000Y296500D03*
X1063000D03*
X1066000D03*
Y293500D03*
X1063000D03*
X1060000D03*
X1069000D03*
X1060000Y299500D03*
X1063000D03*
X1066000D03*
Y305500D03*
X1063000D03*
X1060000D03*
X1066000Y302500D03*
X1063000D03*
X1060000D03*
X1069000Y305500D03*
Y302500D03*
X1066000Y290500D03*
X1063000D03*
X1060000D03*
X1069000D03*
X1072000Y293500D03*
Y305500D03*
Y302500D03*
Y290500D03*
X1066000Y338000D03*
X1063000D03*
X1060000D03*
X1069000D03*
X1072000D03*
X1067679Y317942D03*
X1061600Y323742D03*
X1060000Y344000D03*
X1063000D03*
X1066000D03*
X1060000Y347000D03*
X1063000D03*
X1066000D03*
Y341000D03*
X1063000D03*
X1060000D03*
X1066000Y353000D03*
X1063000D03*
X1060000D03*
X1066000Y350000D03*
X1063000D03*
X1060000D03*
X1069000Y353000D03*
Y350000D03*
Y341000D03*
X1072000Y353000D03*
Y350000D03*
Y341000D03*
X1067707Y365442D03*
X1061600Y359642D03*
X1066000Y397500D03*
X1063000D03*
X1060000D03*
X1069000D03*
X1060000Y391500D03*
X1063000D03*
X1066000D03*
X1060000Y394500D03*
X1063000D03*
X1066000D03*
Y388500D03*
X1063000D03*
X1060000D03*
X1066000Y385500D03*
X1063000D03*
X1060000D03*
X1069000Y388500D03*
Y385500D03*
X1072000Y397500D03*
Y388500D03*
Y385500D03*
X1066000Y400500D03*
X1063000D03*
X1060000D03*
X1069000D03*
X1072000D03*
X1067531Y412942D03*
X1060984Y418742D03*
X1066000Y433000D03*
X1063000D03*
X1060000D03*
X1069000D03*
X1060000Y439000D03*
X1063000D03*
X1066000D03*
X1060000Y442000D03*
X1063000D03*
X1066000D03*
Y436000D03*
X1063000D03*
X1060000D03*
X1069000D03*
X1072000Y433000D03*
Y436000D03*
X1066000Y448000D03*
X1063000D03*
X1060000D03*
X1066000Y445000D03*
X1063000D03*
X1060000D03*
X1069000Y448000D03*
Y445000D03*
X1072000Y448000D03*
Y445000D03*
X1069000Y480500D03*
Y483500D03*
X1060000Y480500D03*
X1063000D03*
X1066000D03*
X1060000Y483500D03*
X1063000D03*
X1066000D03*
Y486500D03*
X1063000D03*
X1060000D03*
X1072000Y480500D03*
Y483500D03*
X1067730Y460352D03*
X1061600Y466242D03*
X1069000Y492500D03*
Y495500D03*
X1060000Y492500D03*
X1063000D03*
X1066000D03*
X1060000Y495500D03*
X1063000D03*
X1066000D03*
Y489500D03*
X1063000D03*
X1060000D03*
X1072000Y492500D03*
Y495500D03*
X1067866Y507629D03*
X1061600Y513742D03*
X1066500Y538000D03*
Y541000D03*
X1069500D03*
X1066500Y544000D03*
X1069500D03*
Y538000D03*
X1060498Y575739D03*
X1069500Y547000D03*
Y550000D03*
X1066500Y547000D03*
Y550000D03*
Y553000D03*
X1069500D03*
X1094582Y3004D03*
X1074582D03*
X1097100Y35582D03*
Y38582D03*
X1099600D03*
Y35582D03*
X1102100D03*
Y38582D03*
X1096961Y18126D03*
Y21126D03*
X1099461D03*
Y18126D03*
X1101961D03*
Y21126D03*
X1097101Y53737D03*
Y56737D03*
X1099601D03*
Y53737D03*
X1102101D03*
Y56737D03*
X1091000Y99500D03*
X1095100D03*
X1092000Y82500D03*
X1087000Y100000D03*
X1073200Y90900D03*
X1077200D03*
X1073200Y126000D03*
Y128800D03*
Y123200D03*
X1084740Y108000D03*
X1084325Y130197D03*
X1100075Y139925D03*
X1084260Y152600D03*
X1094493Y151856D03*
X1073154Y137800D03*
X1082000Y143600D03*
X1092000Y159500D03*
X1094500Y143144D03*
X1084401Y159260D03*
X1094024Y179500D03*
X1085000Y184575D03*
X1079500D03*
X1085525Y167500D03*
Y171000D03*
Y174500D03*
Y164000D03*
X1087500Y198000D03*
Y201000D03*
X1097500Y203700D03*
X1100000D03*
X1073500Y191500D03*
X1101903Y285019D03*
X1101796Y331894D03*
X1086500Y356000D03*
X1090500Y376500D03*
X1080418Y373600D03*
X1090443Y417343D03*
X1086500Y403500D03*
X1074316Y406925D03*
X1080498Y575739D03*
X1100498D03*
X1114582Y3004D03*
X1125170Y35582D03*
Y38582D03*
X1127670D03*
Y35582D03*
X1130170D03*
Y38582D03*
X1104600Y35582D03*
Y38582D03*
X1107100Y35582D03*
Y38582D03*
X1104461Y18126D03*
Y21126D03*
X1106961Y18126D03*
Y21126D03*
X1130031D03*
Y18126D03*
X1127531D03*
Y21126D03*
X1125031D03*
Y18126D03*
X1104601Y53737D03*
Y56737D03*
X1107101Y53737D03*
Y56737D03*
X1113000Y101240D03*
X1119500Y86000D03*
Y83000D03*
X1123000Y120816D03*
X1126000D03*
X1131500D03*
X1115800Y126600D03*
X1113500Y147500D03*
X1130125Y135940D03*
X1126075Y135973D03*
X1121238Y144500D03*
X1108500Y136500D03*
X1104500Y136524D03*
X1120524Y138457D03*
X1129000Y157000D03*
X1120200D03*
X1115425Y138925D03*
X1119000Y189500D03*
X1111100Y163749D03*
X1123500Y187000D03*
X1108000Y172000D03*
X1113368Y171619D03*
X1113129Y165719D03*
X1114500Y188700D03*
X1120200Y176500D03*
Y166500D03*
X1129000D03*
Y176500D03*
X1108821Y166800D03*
X1125918Y195418D03*
X1129068Y195500D03*
X1133000Y198000D03*
X1117206Y231741D03*
X1117290Y224241D03*
X1106189D03*
X1106106Y231741D03*
X1118774Y284699D03*
X1112902D03*
X1110019Y284806D03*
X1104786Y284912D03*
X1121657Y284592D03*
X1118667Y331574D03*
X1112795D03*
X1109912Y331681D03*
X1104679Y331787D03*
X1121550Y331467D03*
X1104009Y427245D03*
X1120880Y426925D03*
X1115008D03*
X1112125Y427032D03*
X1106892Y427138D03*
X1123763Y426818D03*
X1103800Y474339D03*
X1106683Y474232D03*
X1111916Y474126D03*
X1114799Y474019D03*
X1120671D03*
X1123554Y473912D03*
X1111452Y544000D03*
Y541000D03*
X1114452Y544000D03*
Y541000D03*
Y538000D03*
X1111452D03*
X1120669Y544000D03*
Y541000D03*
X1123669Y544000D03*
Y541000D03*
Y538000D03*
X1120669D03*
X1120498Y575739D03*
X1114452Y553000D03*
X1111452D03*
X1114452Y550000D03*
X1111452D03*
X1114452Y547000D03*
X1111452D03*
X1123669Y553000D03*
X1120669D03*
X1123669Y550000D03*
X1120669D03*
X1123669Y547000D03*
X1120669D03*
X1154582Y3004D03*
X1134582D03*
X1132670Y35582D03*
X1135170D03*
Y38582D03*
X1132670D03*
X1135031Y21126D03*
Y18126D03*
X1132531Y21126D03*
Y18126D03*
X1132950Y82867D03*
Y85867D03*
X1135450D03*
Y82867D03*
X1137950D03*
X1140450D03*
X1142950D03*
Y85867D03*
X1140450D03*
X1137950D03*
X1155000Y124913D03*
X1159300Y129700D03*
X1141500Y124425D03*
Y120500D03*
X1134500Y120816D03*
X1154000Y151500D03*
X1141500Y134575D03*
X1158200Y137700D03*
X1136300Y161100D03*
X1140000D03*
X1160200Y175982D03*
X1152781Y165719D03*
X1136300Y172300D03*
X1140000D03*
X1140336Y183560D03*
X1143490D03*
X1152500Y186500D03*
X1158000Y179000D03*
X1138203Y266860D03*
Y260860D03*
Y263860D03*
X1135203Y260860D03*
Y263860D03*
Y266860D03*
X1138203Y257860D03*
Y254860D03*
X1135203Y257860D03*
Y254860D03*
X1159710Y306037D03*
X1156710D03*
X1159710Y303037D03*
X1156710D03*
X1159710Y300037D03*
X1156710D03*
X1159710Y297037D03*
X1156710D03*
Y294037D03*
X1159710D03*
Y309037D03*
X1156710D03*
X1135403Y302360D03*
Y305360D03*
X1138403Y302360D03*
Y305360D03*
X1135403Y308360D03*
X1138403D03*
X1159710Y312037D03*
X1156710D03*
X1159710Y321037D03*
X1156710D03*
X1159710Y318037D03*
X1156710D03*
X1159710Y315037D03*
X1156710D03*
X1135403Y314360D03*
Y311360D03*
X1138403D03*
Y314360D03*
Y361979D03*
X1135403D03*
X1138403Y358979D03*
X1135403D03*
X1138403Y355979D03*
X1135403D03*
X1138403Y352979D03*
X1135403D03*
X1138403Y349979D03*
X1135403D03*
X1135190Y396965D03*
X1138190D03*
X1135190Y399965D03*
X1138190D03*
X1135190Y402965D03*
Y405965D03*
Y408965D03*
X1138190Y402965D03*
Y405965D03*
Y408965D03*
X1159799Y448537D03*
X1156799D03*
X1159799Y445537D03*
X1156799D03*
X1159799Y442537D03*
X1156799D03*
X1159799Y439537D03*
X1156799D03*
Y436537D03*
X1159799D03*
Y454537D03*
X1156799D03*
X1159799Y451537D03*
X1156799D03*
X1135404Y457228D03*
Y454228D03*
Y451228D03*
Y445228D03*
Y448228D03*
X1138404Y454228D03*
Y451228D03*
Y445228D03*
Y448228D03*
Y457228D03*
X1159799Y457537D03*
X1156799D03*
X1159799Y463537D03*
X1156799D03*
X1159799Y460537D03*
X1156799D03*
X1135622Y485732D03*
Y470732D03*
Y467732D03*
Y479732D03*
Y476732D03*
Y473732D03*
Y482732D03*
X1138622D03*
Y473732D03*
Y476732D03*
Y479732D03*
Y470732D03*
Y485732D03*
Y467732D03*
X1140498Y575739D03*
X1160498D03*
X1174582Y3004D03*
X1183321Y123652D03*
X1185821D03*
X1188321D03*
Y120652D03*
X1185821D03*
X1183321D03*
X1180821D03*
Y123652D03*
X1178321D03*
Y120652D03*
X1177475Y111500D03*
X1179500Y105500D03*
X1162700Y175959D03*
X1183021Y165952D03*
X1185521D03*
X1188600Y166000D03*
X1188618Y162782D03*
X1185521Y162952D03*
X1183021D03*
X1180521D03*
Y165952D03*
X1177521D03*
Y162952D03*
X1167600Y184500D03*
Y180500D03*
X1174500Y214000D03*
Y211000D03*
Y208000D03*
Y205000D03*
X1171500D03*
Y208000D03*
Y211000D03*
Y214000D03*
X1179651Y305942D03*
X1162710Y306037D03*
Y303037D03*
Y300037D03*
Y297037D03*
Y294037D03*
Y309037D03*
X1179651Y309942D03*
X1165070Y328750D03*
X1193411D03*
X1179411Y334250D03*
Y337750D03*
X1162710Y312037D03*
Y321037D03*
Y318037D03*
Y315037D03*
X1179411Y330750D03*
Y327250D03*
X1180986Y349234D03*
X1177836D03*
X1179877Y452442D03*
Y448442D03*
X1162799Y448537D03*
Y445537D03*
Y442537D03*
Y439537D03*
Y436537D03*
Y454537D03*
Y451537D03*
Y457537D03*
X1165190Y471250D03*
X1179500Y476750D03*
Y480250D03*
X1162799Y463537D03*
Y460537D03*
X1179500Y469750D03*
Y473250D03*
X1181075Y491734D03*
X1177925D03*
X1180498Y575739D03*
X1214582Y3004D03*
X1194582D03*
X1203887Y306894D03*
X1200887D03*
X1197887D03*
X1203887Y303894D03*
X1200887D03*
X1197887D03*
X1203887Y300894D03*
X1200887D03*
X1197887D03*
X1203887Y297894D03*
X1200887D03*
X1197887D03*
X1203887Y294894D03*
X1200887D03*
X1197887D03*
Y321894D03*
X1200887D03*
X1203887D03*
Y318894D03*
X1200887D03*
X1197887D03*
X1203887Y315894D03*
X1200887D03*
X1197887D03*
X1203887Y312894D03*
X1200887D03*
X1197887D03*
X1203887Y309894D03*
X1200887D03*
X1197887D03*
X1197976Y437394D03*
X1200976D03*
X1203976D03*
X1197976Y440394D03*
X1200976D03*
X1203976D03*
X1197976Y443394D03*
X1200976D03*
X1203976D03*
X1197976Y446394D03*
X1200976D03*
X1203976D03*
X1197976Y449394D03*
X1200976D03*
X1203976D03*
X1197976Y452394D03*
X1200976D03*
X1203976D03*
X1197976Y455394D03*
X1200976D03*
X1203976D03*
X1197976Y464394D03*
X1200976D03*
X1203976D03*
X1197976Y458394D03*
X1200976D03*
X1203976D03*
X1197976Y461394D03*
X1200976D03*
X1203976D03*
X1193840Y471250D03*
X1200498Y575739D03*
X1220498D03*
X1234582Y3004D03*
X1240498Y575739D03*
X1277657Y4128D03*
X1254582Y3004D03*
X1260498Y575739D03*
X1279438Y573806D03*
X1286766Y12634D03*
X1288331Y30962D03*
Y70962D03*
Y50962D03*
Y90962D03*
Y130962D03*
Y110962D03*
Y150962D03*
Y190962D03*
Y170962D03*
Y210962D03*
Y230962D03*
Y270962D03*
Y250962D03*
Y290962D03*
Y330962D03*
Y310962D03*
Y350962D03*
Y390962D03*
Y370962D03*
Y410962D03*
Y450962D03*
Y430962D03*
Y470962D03*
Y510962D03*
Y490962D03*
Y530962D03*
X1287616Y563889D03*
X1288331Y550962D03*
G54D104*
G01X181271Y212651D02*
X184349D01*
G01X1041500Y189075D02*
X1039016D01*
G01X1041500Y185925D02*
X1039016D01*
G01X1070715Y174785D02*
Y178585D01*
G01X1067000Y189075D02*
Y191500D01*
G01X1064500Y276242D02*
X1061600D01*
G01X1064500Y323742D02*
X1061600D01*
G01X1064500Y359642D02*
X1061600D01*
G01X1064500Y418742D02*
X1060984D01*
G01X1064500Y466242D02*
X1061600D01*
G01X1064500Y513742D02*
X1061600D01*
G01X1091000Y97075D02*
Y99500D01*
G01X1095100Y97075D02*
Y99500D01*
G01X1096260Y82500D02*
X1092000D01*
G01X1096893Y156099D02*
Y151856D01*
G01D02*
X1094493D01*
G01X1075834Y150749D02*
Y159366D01*
X1073274Y161926D01*
Y174785D01*
G01X1096425Y179500D02*
X1094024D01*
G01X1109724Y101240D02*
X1113000D01*
G01X1115900Y83000D02*
X1119500D01*
G01X1113075Y88000D02*
X1117500D01*
X1119500Y86000D01*
G01X1108500Y138925D02*
Y136500D01*
G01X1104500Y138925D02*
Y136524D01*
G01X1122925Y138457D02*
X1120524D01*
G01X1108590Y224241D02*
X1106189D01*
G01X1151535Y124913D02*
X1155000D01*
G01X1152500Y172964D02*
Y186500D01*
G01X1133000Y195575D02*
Y198000D01*
G54D11*
X19685Y-614173D03*
Y636929D03*
X175000Y100500D03*
X619685Y636929D03*
X877510Y558620D03*
X964460Y16950D03*
X1271654Y-614173D03*
Y636929D03*
G54D20*
X92110Y300900D03*
X85000Y307310D03*
X77770Y313960D03*
X106230Y287950D03*
X99810Y294370D03*
X144900Y224500D03*
X141664Y239573D03*
X178265Y247712D03*
X171374Y251923D03*
X660100Y39900D03*
X711500Y61300D03*
X792000Y358000D03*
X833500Y268575D03*
X816000Y270525D03*
X827602Y283500D03*
X836500Y302500D03*
X814050Y341450D03*
X819500Y318500D03*
X831750Y318250D03*
X813100Y368600D03*
X827000Y352500D03*
X843500Y268575D03*
X853500D03*
X845000Y303000D03*
X848500Y335800D03*
X840000Y337500D03*
Y363000D03*
Y345500D03*
X843843Y354342D03*
X849000Y399000D03*
X870000Y304525D03*
X880000D03*
X870000Y312788D03*
X880000Y312855D03*
X875000Y347273D03*
X905941Y320366D03*
X916260Y355000D03*
X923740Y345500D03*
X940000Y283800D03*
X935516Y361075D03*
X933357Y344843D03*
X933196Y353360D03*
X1028940Y182130D03*
X1034290Y197990D03*
X1050220Y126510D03*
X1053505Y144080D03*
X1053000Y136500D03*
X1064500Y166000D03*
X1059500Y175500D03*
X1054000Y181000D03*
X1066000Y175500D03*
X1062500Y181000D03*
X1091000Y89000D03*
X1094500Y103000D03*
X1077400Y141300D03*
X1115500Y97500D03*
X1121000Y94500D03*
X1127148Y147566D03*
X1118000Y146000D03*
X1106500Y155000D03*
X1105000Y147500D03*
X1112500Y151000D03*
X1105500Y161779D03*
X1110925Y187500D03*
X1110800Y170000D03*
X1131088Y186912D03*
X1108500Y176000D03*
X1105170Y182630D03*
X1153845Y161098D03*
X1158750Y144750D03*
X1137808Y187588D03*
X1135000Y220600D03*
X1136600Y228060D03*
X1189000Y248500D03*
Y266000D03*
X1190500Y420000D03*
Y402500D03*
X1230000Y458000D03*
X1248000D03*
G54D105*
G01X161737Y535198D02*
X165539Y539000D01*
G01D02*
X169341Y542802D01*
G01X161737D02*
X165539Y539000D01*
G01D02*
X169341Y535198D01*
G01X209737D02*
X213539Y539000D01*
G01D02*
X217341Y542802D01*
G01X209737D02*
X213539Y539000D01*
G01D02*
X217341Y535198D01*
G01X264298Y236298D02*
X268000Y240000D01*
G01D02*
X271702Y243702D01*
G01X264298D02*
X268000Y240000D01*
G01D02*
X271702Y236298D01*
G01X257737Y535198D02*
X261539Y539000D01*
G01D02*
X265341Y542802D01*
G01X257737D02*
X261539Y539000D01*
G01D02*
X265341Y535198D01*
G01X308798Y236298D02*
X312500Y240000D01*
G01D02*
X316202Y243702D01*
G01X308798D02*
X312500Y240000D01*
G01D02*
X316202Y236298D01*
G01X319217Y535198D02*
X323019Y539000D01*
G01D02*
X326821Y542802D01*
G01X319217D02*
X323019Y539000D01*
G01D02*
X326821Y535198D01*
G01X353298Y236298D02*
X357000Y240000D01*
G01D02*
X360702Y243702D01*
G01X353298D02*
X357000Y240000D01*
G01D02*
X360702Y236298D01*
G01X367217Y535198D02*
X371019Y539000D01*
G01D02*
X374821Y542802D01*
G01X367217D02*
X371019Y539000D01*
G01D02*
X374821Y535198D01*
G01X415217D02*
X419019Y539000D01*
G01D02*
X422821Y542802D01*
G01X415217D02*
X419019Y539000D01*
G01D02*
X422821Y535198D01*
G01X424798Y236298D02*
X428500Y240000D01*
G01D02*
X432202Y243702D01*
G01X424798D02*
X428500Y240000D01*
G01D02*
X432202Y236298D01*
G01X468798D02*
X472500Y240000D01*
G01D02*
X476202Y243702D01*
G01X468798D02*
X472500Y240000D01*
G01D02*
X476202Y236298D01*
G01X476698Y535198D02*
X480500Y539000D01*
G01D02*
X484302Y542802D01*
G01X476698D02*
X480500Y539000D01*
G01D02*
X484302Y535198D01*
G01X512798Y236298D02*
X516500Y240000D01*
G01D02*
X520202Y243702D01*
G01X512798D02*
X516500Y240000D01*
G01D02*
X520202Y236298D01*
G01X524698Y535198D02*
X528500Y539000D01*
G01D02*
X532302Y542802D01*
G01X524698D02*
X528500Y539000D01*
G01D02*
X532302Y535198D01*
G01X574798Y236298D02*
X578500Y240000D01*
G01D02*
X582202Y243702D01*
G01X574798D02*
X578500Y240000D01*
G01D02*
X582202Y236298D01*
G01X572698Y535198D02*
X576500Y539000D01*
G01D02*
X580302Y542802D01*
G01X572698D02*
X576500Y539000D01*
G01D02*
X580302Y535198D01*
G01X618798Y236298D02*
X622500Y240000D01*
G01D02*
X626202Y243702D01*
G01X618798D02*
X622500Y240000D01*
G01D02*
X626202Y236298D01*
G01X634179Y535198D02*
X637981Y539000D01*
G01D02*
X641783Y542802D01*
G01X634179D02*
X637981Y539000D01*
G01D02*
X641783Y535198D01*
G01X662798Y236298D02*
X666500Y240000D01*
G01D02*
X670202Y243702D01*
G01X662798D02*
X666500Y240000D01*
G01D02*
X670202Y236298D01*
G01X682179Y535198D02*
X685981Y539000D01*
G01D02*
X689783Y542802D01*
G01X682179D02*
X685981Y539000D01*
G01D02*
X689783Y535198D01*
G01X732279Y236298D02*
X735981Y240000D01*
G01D02*
X739683Y243702D01*
G01X732279D02*
X735981Y240000D01*
G01D02*
X739683Y236298D01*
G01X730179Y535198D02*
X733981Y539000D01*
G01D02*
X737783Y542802D01*
G01X730179D02*
X733981Y539000D01*
G01D02*
X737783Y535198D01*
G01X776279Y236298D02*
X779981Y240000D01*
G01X776279Y243702D02*
X779981Y240000D01*
G01D02*
X783683Y243702D01*
G01X779981Y240000D02*
X783683Y236298D01*
G01X820279D02*
X823981Y240000D01*
G01D02*
X827683Y243702D01*
G01X820279D02*
X823981Y240000D01*
G01D02*
X827683Y236298D01*
G54D21*
X118126Y258500D03*
X133874D03*
G54D30*
X181384Y224820D03*
X181324Y242330D03*
X162041Y241140D03*
X181324Y231330D03*
Y220830D03*
Y238330D03*
X704484Y32000D03*
X697484D03*
X697519Y36695D03*
X697484Y27000D03*
X704519Y36695D03*
X755984Y27500D03*
Y68500D03*
X1041584Y193700D03*
X1044038Y143267D03*
X1089484Y103000D03*
X1099952Y160413D03*
X1100016Y143144D03*
X1099984Y147500D03*
X1099952Y156099D03*
Y151856D03*
X1112984Y88000D03*
X1129652Y142556D03*
X1103484Y173500D03*
X1128977Y192756D03*
X1133184Y138457D03*
X1174984Y111500D03*
G54D12*
X72836Y47244D03*
Y535433D03*
X466536Y47244D03*
X860237D03*
X943225Y228000D03*
X985225Y542500D03*
G54D106*
G01X173774Y272159D02*
X178819Y277204D01*
G01D02*
X183864Y282249D01*
G01X173774D02*
X178819Y277204D01*
G01D02*
X183864Y272159D01*
G01X188774D02*
X193819Y277204D01*
G01D02*
X198864Y282249D01*
G01X188774D02*
X193819Y277204D01*
G01X198864Y272159D02*
X193819Y277204D01*
G01X248774Y272159D02*
X253819Y277204D01*
G01D02*
X258864Y282249D01*
G01X248774D02*
X253819Y277204D01*
G01D02*
X258864Y272159D01*
G01X263774D02*
X268819Y277204D01*
G01D02*
X273864Y282249D01*
G01X263774D02*
X268819Y277204D01*
G01D02*
X273864Y272159D01*
G01X248467Y471852D02*
X253819Y477204D01*
G01D02*
X259171Y482556D01*
G01X248467D02*
X253819Y477204D01*
G01D02*
X259171Y471852D01*
G01X421254Y272159D02*
X426299Y277204D01*
G01X411299D02*
X416344Y272159D01*
G01X406254Y282249D02*
X411299Y277204D01*
G01D02*
X416344Y282249D01*
G01X406254Y272159D02*
X411299Y277204D01*
G01X421254Y282249D02*
X426299Y277204D01*
G01X405947Y471852D02*
X411299Y477204D01*
G01D02*
X416651Y482556D01*
G01X405947D02*
X411299Y477204D01*
G01D02*
X416651Y471852D01*
G01X426299Y277204D02*
X431344Y272159D01*
G01X426299Y277204D02*
X431344Y282249D01*
G01X568780Y277204D02*
X573825Y272159D01*
G01X563735Y282249D02*
X568780Y277204D01*
G01D02*
X573825Y282249D01*
G01X563735Y272159D02*
X568780Y277204D01*
G01X563428Y471852D02*
X568780Y477204D01*
G01D02*
X574132Y482556D01*
G01X563428D02*
X568780Y477204D01*
G01D02*
X574132Y471852D01*
G01X578735Y282249D02*
X583780Y277204D01*
G01X578735Y272159D02*
X583780Y277204D01*
G01D02*
X588825Y272159D01*
G01X583780Y277204D02*
X588825Y282249D01*
G01X736216D02*
X741261Y277204D01*
G01X736216Y272159D02*
X741261Y277204D01*
G01X726261D02*
X731306Y272159D01*
G01X721216Y282249D02*
X726261Y277204D01*
G01D02*
X731306Y282249D01*
G01X721216Y272159D02*
X726261Y277204D01*
G01X741261D02*
X746306Y272159D01*
G01X741261Y277204D02*
X746306Y282249D01*
G01X720909Y471852D02*
X726261Y477204D01*
G01D02*
X731613Y482556D01*
G01X720909D02*
X726261Y477204D01*
G01D02*
X731613Y471852D01*
G54D40*
X181839Y503500D03*
X170239D03*
X181839Y512500D03*
X170239D03*
X229839D03*
X218239D03*
X229839Y503500D03*
X218239D03*
X266239D03*
Y512500D03*
X277839Y503500D03*
Y512500D03*
X327719Y503500D03*
Y512500D03*
X339319Y503500D03*
Y512500D03*
X387319D03*
X375719D03*
X387319Y503500D03*
X375719D03*
X435319D03*
X423719D03*
X435319Y512500D03*
X423719D03*
X496800D03*
X485200D03*
X496800Y503500D03*
X485200D03*
X533200D03*
Y512500D03*
X544800Y503500D03*
Y512500D03*
X592800D03*
X581200D03*
X592800Y503500D03*
X581200D03*
X654281Y512500D03*
X642681D03*
X654281Y503500D03*
X642681D03*
X702281Y512500D03*
X690681D03*
X702281Y503500D03*
X690681D03*
X738681Y512500D03*
Y503500D03*
X750281Y512500D03*
Y503500D03*
G54D22*
X153180Y215785D03*
Y218935D03*
X141840Y234905D03*
Y231755D03*
X181271Y212651D03*
Y209501D03*
X691400Y50875D03*
Y47725D03*
G54D31*
X178417Y224820D03*
X178357Y242330D03*
X159074Y241140D03*
X178357Y231330D03*
Y220830D03*
Y238330D03*
X701517Y32000D03*
X694517D03*
X694552Y36695D03*
X694517Y27000D03*
X701552Y36695D03*
X753017Y27500D03*
Y68500D03*
X1041071Y143267D03*
X1038617Y193700D03*
X1086517Y103000D03*
X1096985Y160413D03*
X1097049Y143144D03*
X1097017Y147500D03*
X1096985Y156099D03*
Y151856D03*
X1100517Y173500D03*
X1110017Y88000D03*
X1130217Y138457D03*
X1126685Y142556D03*
X1126010Y192756D03*
X1172017Y111500D03*
G54D13*
X74804Y47244D03*
Y535433D03*
X468504Y47244D03*
X862205D03*
X945193Y228000D03*
X987193Y542500D03*
G54D107*
G01X-297025Y-1013390D02*
Y1828909D01*
X3691357D01*
Y-1013390D01*
X-297025D01*
G01X4093Y-769672D02*
Y-844672D01*
X504093D01*
Y-769672D01*
X4093D01*
G01X16093Y-834672D02*
Y-839672D01*
G01X14636Y-834672D02*
X17550D01*
G01X22460Y-839672D02*
X19926D01*
Y-834672D01*
X22460D01*
G01X21446Y-837089D02*
X19926D01*
G01X25026Y-834672D02*
Y-839672D01*
X27560D01*
G01X31393Y-839839D02*
X31266Y-839755D01*
Y-839589D01*
X31393Y-839505D01*
X31520Y-839589D01*
Y-839755D01*
X31393Y-839839D01*
G01Y-837589D02*
X31266Y-837505D01*
Y-837339D01*
X31393Y-837255D01*
X31520Y-837339D01*
Y-837505D01*
X31393Y-837589D01*
G01X36176Y-841339D02*
X35543Y-840505D01*
X35226Y-839672D01*
Y-836339D01*
X35543Y-835505D01*
X36176Y-834672D01*
G01X41593D02*
X41086Y-834839D01*
X40706Y-835255D01*
X40453Y-835755D01*
X40263Y-836422D01*
X40200Y-837172D01*
X40263Y-837922D01*
X40453Y-838589D01*
X40706Y-839089D01*
X41086Y-839505D01*
X41593Y-839672D01*
X42100Y-839505D01*
X42480Y-839089D01*
X42733Y-838589D01*
X42923Y-837922D01*
X42986Y-837172D01*
X42923Y-836422D01*
X42733Y-835755D01*
X42480Y-835255D01*
X42100Y-834839D01*
X41593Y-834672D01*
G01X45300Y-838672D02*
X45680Y-839255D01*
X46186Y-839589D01*
X46756Y-839672D01*
X47263Y-839589D01*
X47770Y-839172D01*
X48086Y-838672D01*
X48150Y-838172D01*
X48023Y-837589D01*
X47580Y-837172D01*
X47136Y-837005D01*
X46566D01*
G01X47136D02*
X47516Y-836755D01*
X47833Y-836339D01*
X47960Y-835839D01*
X47833Y-835339D01*
X47516Y-834922D01*
X46946Y-834672D01*
X46376Y-834755D01*
X45806Y-835089D01*
G01X52110Y-841339D02*
X52743Y-840505D01*
X53060Y-839672D01*
Y-836339D01*
X52743Y-835505D01*
X52110Y-834672D01*
G01X55500Y-838672D02*
X55880Y-839255D01*
X56386Y-839589D01*
X56956Y-839672D01*
X57463Y-839589D01*
X57970Y-839172D01*
X58286Y-838672D01*
X58350Y-838172D01*
X58223Y-837589D01*
X57780Y-837172D01*
X57336Y-837005D01*
X56766D01*
G01X57336D02*
X57716Y-836755D01*
X58033Y-836339D01*
X58160Y-835839D01*
X58033Y-835339D01*
X57716Y-834922D01*
X57146Y-834672D01*
X56576Y-834755D01*
X56006Y-835089D01*
G01X60790Y-835505D02*
X61170Y-835005D01*
X61613Y-834755D01*
X62120Y-834672D01*
X62753Y-834839D01*
X63196Y-835255D01*
X63323Y-835755D01*
X63260Y-836255D01*
X63006Y-836672D01*
X61740Y-837505D01*
X61170Y-838089D01*
X60790Y-838922D01*
X60663Y-839672D01*
X63323D01*
G01X66966D02*
X67093Y-838589D01*
X67283Y-837672D01*
X67536Y-836839D01*
X67853Y-835922D01*
X68360Y-834672D01*
X65826D01*
G01X71370Y-838005D02*
X73016D01*
G01X76090Y-835505D02*
X76470Y-835005D01*
X76913Y-834755D01*
X77420Y-834672D01*
X78053Y-834839D01*
X78496Y-835255D01*
X78623Y-835755D01*
X78560Y-836255D01*
X78306Y-836672D01*
X77040Y-837505D01*
X76470Y-838089D01*
X76090Y-838922D01*
X75963Y-839672D01*
X78623D01*
G01X81000Y-838672D02*
X81380Y-839255D01*
X81886Y-839589D01*
X82456Y-839672D01*
X82963Y-839589D01*
X83470Y-839172D01*
X83786Y-838672D01*
X83850Y-838172D01*
X83723Y-837589D01*
X83280Y-837172D01*
X82836Y-837005D01*
X82266D01*
G01X82836D02*
X83216Y-836755D01*
X83533Y-836339D01*
X83660Y-835839D01*
X83533Y-835339D01*
X83216Y-834922D01*
X82646Y-834672D01*
X82076Y-834755D01*
X81506Y-835089D01*
G01X88253Y-839672D02*
Y-834672D01*
X85910Y-838255D01*
X89076D01*
G01X91200Y-838922D02*
X91580Y-839339D01*
X92023Y-839589D01*
X92593Y-839672D01*
X93163Y-839505D01*
X93606Y-839172D01*
X93923Y-838589D01*
X93986Y-837922D01*
X93860Y-837255D01*
X93543Y-836839D01*
X93100Y-836505D01*
X92656Y-836422D01*
X92213Y-836505D01*
X91643Y-836839D01*
X91833Y-834672D01*
X93543D01*
G01X101590Y-839672D02*
Y-834672D01*
X103996D01*
G01X103110Y-837089D02*
X101590D01*
G01X106310Y-839672D02*
X107893Y-834672D01*
X109476Y-839672D01*
G01X108906Y-837922D02*
X106880D01*
G01X111663Y-839672D02*
X114323Y-834672D01*
G01X111663D02*
X114323Y-839672D01*
G01X118093Y-839839D02*
X117966Y-839755D01*
Y-839589D01*
X118093Y-839505D01*
X118220Y-839589D01*
Y-839755D01*
X118093Y-839839D01*
G01Y-837589D02*
X117966Y-837505D01*
Y-837339D01*
X118093Y-837255D01*
X118220Y-837339D01*
Y-837505D01*
X118093Y-837589D01*
G01X122876Y-841339D02*
X122243Y-840505D01*
X121926Y-839672D01*
Y-836339D01*
X122243Y-835505D01*
X122876Y-834672D01*
G01X128293D02*
X127786Y-834839D01*
X127406Y-835255D01*
X127153Y-835755D01*
X126963Y-836422D01*
X126900Y-837172D01*
X126963Y-837922D01*
X127153Y-838589D01*
X127406Y-839089D01*
X127786Y-839505D01*
X128293Y-839672D01*
X128800Y-839505D01*
X129180Y-839089D01*
X129433Y-838589D01*
X129623Y-837922D01*
X129686Y-837172D01*
X129623Y-836422D01*
X129433Y-835755D01*
X129180Y-835255D01*
X128800Y-834839D01*
X128293Y-834672D01*
G01X132000Y-838672D02*
X132380Y-839255D01*
X132886Y-839589D01*
X133456Y-839672D01*
X133963Y-839589D01*
X134470Y-839172D01*
X134786Y-838672D01*
X134850Y-838172D01*
X134723Y-837589D01*
X134280Y-837172D01*
X133836Y-837005D01*
X133266D01*
G01X133836D02*
X134216Y-836755D01*
X134533Y-836339D01*
X134660Y-835839D01*
X134533Y-835339D01*
X134216Y-834922D01*
X133646Y-834672D01*
X133076Y-834755D01*
X132506Y-835089D01*
G01X138810Y-841339D02*
X139443Y-840505D01*
X139760Y-839672D01*
Y-836339D01*
X139443Y-835505D01*
X138810Y-834672D01*
G01X142200Y-838672D02*
X142580Y-839255D01*
X143086Y-839589D01*
X143656Y-839672D01*
X144163Y-839589D01*
X144670Y-839172D01*
X144986Y-838672D01*
X145050Y-838172D01*
X144923Y-837589D01*
X144480Y-837172D01*
X144036Y-837005D01*
X143466D01*
G01X144036D02*
X144416Y-836755D01*
X144733Y-836339D01*
X144860Y-835839D01*
X144733Y-835339D01*
X144416Y-834922D01*
X143846Y-834672D01*
X143276Y-834755D01*
X142706Y-835089D01*
G01X147616Y-839089D02*
X148060Y-839505D01*
X148566Y-839672D01*
X149073Y-839505D01*
X149516Y-839005D01*
X149833Y-838255D01*
X149960Y-837505D01*
Y-836589D01*
X149833Y-835839D01*
X149516Y-835172D01*
X149136Y-834839D01*
X148693Y-834672D01*
X148186Y-834839D01*
X147806Y-835172D01*
X147553Y-835672D01*
X147426Y-836339D01*
X147553Y-836922D01*
X147870Y-837505D01*
X148250Y-837839D01*
X148693Y-837922D01*
X149200Y-837755D01*
X149580Y-837339D01*
X149960Y-836589D01*
G01X153666Y-839672D02*
X153793Y-838589D01*
X153983Y-837672D01*
X154236Y-836839D01*
X154553Y-835922D01*
X155060Y-834672D01*
X152526D01*
G01X158070Y-838005D02*
X159716D01*
G01X162600Y-838672D02*
X162980Y-839255D01*
X163486Y-839589D01*
X164056Y-839672D01*
X164563Y-839589D01*
X165070Y-839172D01*
X165386Y-838672D01*
X165450Y-838172D01*
X165323Y-837589D01*
X164880Y-837172D01*
X164436Y-837005D01*
X163866D01*
G01X164436D02*
X164816Y-836755D01*
X165133Y-836339D01*
X165260Y-835839D01*
X165133Y-835339D01*
X164816Y-834922D01*
X164246Y-834672D01*
X163676Y-834755D01*
X163106Y-835089D01*
G01X167890Y-837589D02*
X168333Y-837005D01*
X168713Y-836672D01*
X169220Y-836505D01*
X169663Y-836672D01*
X169980Y-837005D01*
X170233Y-837505D01*
X170296Y-838089D01*
X170233Y-838589D01*
X169980Y-839089D01*
X169600Y-839505D01*
X169156Y-839672D01*
X168650Y-839505D01*
X168206Y-839005D01*
X167953Y-838255D01*
X167890Y-837422D01*
X168016Y-836339D01*
X168206Y-835755D01*
X168523Y-835172D01*
X168966Y-834755D01*
X169410Y-834672D01*
X169853Y-834839D01*
X170170Y-835255D01*
G01X174193Y-839672D02*
Y-834672D01*
X173433Y-835672D01*
G01Y-839672D02*
X174953D01*
G01X180053D02*
Y-834672D01*
X177710Y-838255D01*
X180876D01*
G01X199093Y-769672D02*
Y-844672D01*
G01Y-819672D02*
X302093D01*
Y-794672D01*
G01X199093D02*
X302093D01*
G01X309600Y-829672D02*
Y-824672D01*
X310866D01*
X311373Y-824922D01*
X311753Y-825255D01*
X312070Y-825755D01*
X312323Y-826339D01*
X312386Y-827172D01*
X312323Y-828005D01*
X312070Y-828589D01*
X311753Y-829089D01*
X311373Y-829422D01*
X310866Y-829672D01*
X309600D01*
G01X314510D02*
X316093Y-824672D01*
X317676Y-829672D01*
G01X317106Y-827922D02*
X315080D01*
G01X321193Y-824672D02*
Y-829672D01*
G01X319736Y-824672D02*
X322650D01*
G01X327560Y-829672D02*
X325026D01*
Y-824672D01*
X327560D01*
G01X326546Y-827089D02*
X325026D01*
G01X331393Y-829839D02*
X331266Y-829755D01*
Y-829589D01*
X331393Y-829505D01*
X331520Y-829589D01*
Y-829755D01*
X331393Y-829839D01*
G01Y-827589D02*
X331266Y-827505D01*
Y-827339D01*
X331393Y-827255D01*
X331520Y-827339D01*
Y-827505D01*
X331393Y-827589D01*
G01X304093Y-769672D02*
Y-844672D01*
G01X302093Y-769672D02*
Y-844672D01*
G01X304093Y-819672D02*
X504093D01*
G01X309726Y-804672D02*
Y-799672D01*
X311246D01*
X311753Y-799922D01*
X312133Y-800505D01*
X312260Y-801172D01*
X312133Y-801839D01*
X311816Y-802339D01*
X311246Y-802589D01*
X309726D01*
G01X314953Y-804839D02*
X317233Y-799672D01*
G01X319736Y-804672D02*
Y-799672D01*
X322650Y-804672D01*
Y-799672D01*
G01X326293Y-804839D02*
X326166Y-804755D01*
Y-804589D01*
X326293Y-804505D01*
X326420Y-804589D01*
Y-804755D01*
X326293Y-804839D01*
G01Y-802589D02*
X326166Y-802505D01*
Y-802339D01*
X326293Y-802255D01*
X326420Y-802339D01*
Y-802505D01*
X326293Y-802589D01*
G01X304093Y-794672D02*
X504093D01*
G01X309726Y-779672D02*
Y-774672D01*
X311246D01*
X311753Y-774922D01*
X312133Y-775505D01*
X312260Y-776172D01*
X312133Y-776839D01*
X311816Y-777339D01*
X311246Y-777589D01*
X309726D01*
G01X314826Y-779672D02*
Y-774672D01*
X316410D01*
X316916Y-774922D01*
X317233Y-775255D01*
X317360Y-775922D01*
X317233Y-776589D01*
X316853Y-777005D01*
X316410Y-777255D01*
X314826D01*
G01X316410D02*
X317360Y-779672D01*
G01X321193D02*
X320686Y-779589D01*
X320243Y-779255D01*
X319863Y-778755D01*
X319610Y-778172D01*
X319483Y-777505D01*
Y-776839D01*
X319610Y-776172D01*
X319863Y-775589D01*
X320243Y-775089D01*
X320686Y-774755D01*
X321193Y-774672D01*
X321700Y-774755D01*
X322143Y-775089D01*
X322523Y-775589D01*
X322776Y-776172D01*
X322903Y-776839D01*
Y-777505D01*
X322776Y-778172D01*
X322523Y-778755D01*
X322143Y-779255D01*
X321700Y-779589D01*
X321193Y-779672D01*
G01X325026Y-778672D02*
X325343Y-779172D01*
X325723Y-779505D01*
X326166Y-779672D01*
X326673Y-779505D01*
X327053Y-779172D01*
X327433Y-778672D01*
X327560Y-778005D01*
Y-774672D01*
G01X332660Y-779672D02*
X330126D01*
Y-774672D01*
X332660D01*
G01X331646Y-777089D02*
X330126D01*
G01X337886Y-775089D02*
X337506Y-774839D01*
X337063Y-774672D01*
X336556D01*
X335986Y-774922D01*
X335543Y-775339D01*
X335226Y-775839D01*
X334973Y-776672D01*
X334910Y-777422D01*
X335036Y-778172D01*
X335226Y-778672D01*
X335606Y-779172D01*
X336050Y-779505D01*
X336493Y-779672D01*
X336936D01*
X337380Y-779505D01*
X337760Y-779255D01*
X338076Y-778922D01*
G01X341593Y-774672D02*
Y-779672D01*
G01X340136Y-774672D02*
X343050D01*
G01X346693Y-779839D02*
X346566Y-779755D01*
Y-779589D01*
X346693Y-779505D01*
X346820Y-779589D01*
Y-779755D01*
X346693Y-779839D01*
G01Y-777589D02*
X346566Y-777505D01*
Y-777339D01*
X346693Y-777255D01*
X346820Y-777339D01*
Y-777505D01*
X346693Y-777589D01*
G01X419093Y-819672D02*
Y-844672D01*
G01X421726Y-822172D02*
Y-827172D01*
X424260D01*
G01X427333Y-822172D02*
X428853D01*
G01X428093D02*
Y-827172D01*
G01X427333D02*
X428853D01*
G01X433700Y-824505D02*
X433953Y-824255D01*
X434143Y-823839D01*
X434270Y-823255D01*
X434143Y-822755D01*
X433890Y-822422D01*
X433446Y-822172D01*
X431736D01*
Y-827172D01*
X433826D01*
X434270Y-826839D01*
X434523Y-826339D01*
X434650Y-825755D01*
X434523Y-825172D01*
X434143Y-824672D01*
X433700Y-824505D01*
X431736D01*
G01X438293Y-827339D02*
X438166Y-827255D01*
Y-827089D01*
X438293Y-827005D01*
X438420Y-827089D01*
Y-827255D01*
X438293Y-827339D01*
G01Y-825089D02*
X438166Y-825005D01*
Y-824839D01*
X438293Y-824755D01*
X438420Y-824839D01*
Y-825005D01*
X438293Y-825089D01*
G01X470106Y-847839D02*
X470213Y-847714D01*
X470293Y-847505D01*
X470346Y-847214D01*
X470293Y-846964D01*
X470186Y-846797D01*
X470000Y-846672D01*
X469280D01*
Y-849172D01*
X470160D01*
X470346Y-849005D01*
X470453Y-848755D01*
X470506Y-848464D01*
X470453Y-848172D01*
X470293Y-847922D01*
X470106Y-847839D01*
X469280D01*
G01X472573Y-849172D02*
Y-847505D01*
G01Y-847797D02*
X472466Y-847630D01*
X472306Y-847547D01*
X472120Y-847505D01*
X471933Y-847589D01*
X471773Y-847755D01*
X471666Y-848005D01*
X471613Y-848339D01*
X471666Y-848672D01*
X471773Y-848922D01*
X471933Y-849089D01*
X472120Y-849172D01*
X472306Y-849130D01*
X472466Y-849005D01*
X472573Y-848839D01*
G01X473893Y-848880D02*
X474026Y-849047D01*
X474213Y-849172D01*
X474373D01*
X474533Y-849089D01*
X474640Y-848964D01*
X474693Y-848797D01*
X474666Y-848547D01*
X474560Y-848422D01*
X474080Y-848172D01*
X473973Y-847880D01*
X474026Y-847672D01*
X474133Y-847547D01*
X474293Y-847505D01*
X474453Y-847547D01*
X474613Y-847672D01*
G01X476093Y-848047D02*
X476946D01*
X476866Y-847755D01*
X476733Y-847589D01*
X476546Y-847505D01*
X476360Y-847547D01*
X476200Y-847672D01*
X476093Y-847964D01*
X476040Y-848214D01*
Y-848464D01*
X476093Y-848714D01*
X476226Y-848964D01*
X476386Y-849130D01*
X476573Y-849172D01*
X476760Y-849089D01*
X476946Y-848839D01*
G01X478213Y-849172D02*
Y-846672D01*
G01Y-847922D02*
X478346Y-847672D01*
X478506Y-847547D01*
X478666Y-847505D01*
X478906Y-847589D01*
X479066Y-847755D01*
X479173Y-848047D01*
Y-848380D01*
X479120Y-848714D01*
X479013Y-848964D01*
X478826Y-849130D01*
X478666Y-849172D01*
X478506Y-849130D01*
X478346Y-849005D01*
X478213Y-848797D01*
G01X480893Y-849172D02*
X480733Y-849130D01*
X480573Y-848964D01*
X480466Y-848672D01*
X480413Y-848339D01*
X480466Y-848005D01*
X480573Y-847714D01*
X480733Y-847547D01*
X480893Y-847505D01*
X481053Y-847547D01*
X481213Y-847714D01*
X481320Y-848005D01*
X481346Y-848339D01*
X481320Y-848672D01*
X481213Y-848964D01*
X481053Y-849130D01*
X480893Y-849172D01*
G01X483573D02*
Y-847505D01*
G01Y-847797D02*
X483466Y-847630D01*
X483306Y-847547D01*
X483120Y-847505D01*
X482933Y-847589D01*
X482773Y-847755D01*
X482666Y-848005D01*
X482613Y-848339D01*
X482666Y-848672D01*
X482773Y-848922D01*
X482933Y-849089D01*
X483120Y-849172D01*
X483306Y-849130D01*
X483466Y-849005D01*
X483573Y-848839D01*
G01X484920Y-849172D02*
Y-847505D01*
G01Y-847839D02*
X485053Y-847672D01*
X485186Y-847547D01*
X485373Y-847505D01*
X485506Y-847547D01*
X485666Y-847672D01*
G01X487973Y-846672D02*
Y-849172D01*
G01Y-848797D02*
X487866Y-849005D01*
X487706Y-849130D01*
X487520Y-849172D01*
X487306Y-849089D01*
X487146Y-848880D01*
X487040Y-848630D01*
X487013Y-848339D01*
X487040Y-848047D01*
X487146Y-847797D01*
X487306Y-847589D01*
X487520Y-847505D01*
X487706Y-847547D01*
X487840Y-847630D01*
X487973Y-847797D01*
G01X491360Y-849172D02*
Y-846672D01*
X492026D01*
X492240Y-846797D01*
X492373Y-846964D01*
X492426Y-847297D01*
X492373Y-847630D01*
X492213Y-847839D01*
X492026Y-847964D01*
X491360D01*
G01X492026D02*
X492426Y-849172D01*
G01X493693Y-848047D02*
X494546D01*
X494466Y-847755D01*
X494333Y-847589D01*
X494146Y-847505D01*
X493960Y-847547D01*
X493800Y-847672D01*
X493693Y-847964D01*
X493640Y-848214D01*
Y-848464D01*
X493693Y-848714D01*
X493826Y-848964D01*
X493986Y-849130D01*
X494173Y-849172D01*
X494360Y-849089D01*
X494546Y-848839D01*
G01X495813Y-847505D02*
X496293Y-849172D01*
X496773Y-847505D01*
G01X498493Y-849255D02*
X498440Y-849214D01*
Y-849130D01*
X498493Y-849089D01*
X498546Y-849130D01*
Y-849214D01*
X498493Y-849255D01*
G01X500693Y-849172D02*
X500880Y-849130D01*
X501093Y-849005D01*
X501226Y-848797D01*
X501280Y-848505D01*
X501226Y-848214D01*
X501066Y-847964D01*
X500826Y-847839D01*
X500560D01*
X500400Y-847755D01*
X500266Y-847547D01*
X500213Y-847255D01*
X500293Y-846964D01*
X500480Y-846755D01*
X500693Y-846672D01*
X500906Y-846755D01*
X501093Y-846964D01*
X501173Y-847255D01*
X501120Y-847547D01*
X500986Y-847755D01*
X500826Y-847839D01*
X500560D01*
X500320Y-847964D01*
X500160Y-848214D01*
X500106Y-848505D01*
X500160Y-848797D01*
X500293Y-849005D01*
X500506Y-849130D01*
X500693Y-849172D01*
G01X503106Y-847839D02*
X503213Y-847714D01*
X503293Y-847505D01*
X503346Y-847214D01*
X503293Y-846964D01*
X503186Y-846797D01*
X503000Y-846672D01*
X502280D01*
Y-849172D01*
X503160D01*
X503346Y-849005D01*
X503453Y-848755D01*
X503506Y-848464D01*
X503453Y-848172D01*
X503293Y-847922D01*
X503106Y-847839D01*
X502280D01*
G01X465993Y-822172D02*
Y-827172D01*
G01X464536Y-822172D02*
X467450D01*
G01X471093Y-827172D02*
X470713Y-827089D01*
X470333Y-826755D01*
X470080Y-826172D01*
X469953Y-825505D01*
X470080Y-824839D01*
X470333Y-824255D01*
X470713Y-823922D01*
X471093Y-823839D01*
X471473Y-823922D01*
X471853Y-824255D01*
X472106Y-824839D01*
X472170Y-825505D01*
X472106Y-826172D01*
X471853Y-826755D01*
X471473Y-827089D01*
X471093Y-827172D01*
G01X476193D02*
X475813Y-827089D01*
X475433Y-826755D01*
X475180Y-826172D01*
X475053Y-825505D01*
X475180Y-824839D01*
X475433Y-824255D01*
X475813Y-823922D01*
X476193Y-823839D01*
X476573Y-823922D01*
X476953Y-824255D01*
X477206Y-824839D01*
X477270Y-825505D01*
X477206Y-826172D01*
X476953Y-826755D01*
X476573Y-827089D01*
X476193Y-827172D01*
G01X481293D02*
Y-822172D01*
G01X486393Y-827339D02*
X486266Y-827255D01*
Y-827089D01*
X486393Y-827005D01*
X486520Y-827089D01*
Y-827255D01*
X486393Y-827339D01*
G01Y-825089D02*
X486266Y-825005D01*
Y-824839D01*
X486393Y-824755D01*
X486520Y-824839D01*
Y-825005D01*
X486393Y-825089D01*
G01X462093Y-819672D02*
Y-844672D01*
G01Y-794672D02*
Y-819672D01*
G01X464726Y-802172D02*
Y-797172D01*
X466310D01*
X466816Y-797422D01*
X467133Y-797755D01*
X467260Y-798422D01*
X467133Y-799089D01*
X466753Y-799505D01*
X466310Y-799755D01*
X464726D01*
G01X466310D02*
X467260Y-802172D01*
G01X472360D02*
X469826D01*
Y-797172D01*
X472360D01*
G01X471346Y-799589D02*
X469826D01*
G01X474610Y-797172D02*
X476193Y-802172D01*
X477776Y-797172D01*
G01X481293Y-802339D02*
X481166Y-802255D01*
Y-802089D01*
X481293Y-802005D01*
X481420Y-802089D01*
Y-802255D01*
X481293Y-802339D01*
G01Y-800089D02*
X481166Y-800005D01*
Y-799839D01*
X481293Y-799755D01*
X481420Y-799839D01*
Y-800005D01*
X481293Y-800089D01*
G01X-297025Y-1013390D02*
Y1828909D01*
X3691357D01*
Y-1013390D01*
X-297025D01*
G01X16913Y-817022D02*
X18480D01*
Y-818912D01*
X18010Y-819542D01*
X17461Y-819962D01*
X16678Y-820172D01*
X15895Y-819962D01*
X15346Y-819542D01*
X14876Y-818912D01*
X14563Y-818177D01*
X14406Y-817337D01*
Y-816602D01*
X14563Y-815972D01*
X14876Y-815237D01*
X15346Y-814607D01*
X15816Y-814187D01*
X16443Y-813872D01*
X16991D01*
X17618Y-814082D01*
X18088Y-814502D01*
G01X21020Y-813872D02*
Y-818387D01*
X21333Y-819332D01*
X21960Y-819962D01*
X22743Y-820172D01*
X23526Y-819962D01*
X24153Y-819332D01*
X24466Y-818387D01*
Y-813872D01*
G01X28103D02*
X29983D01*
G01X29043D02*
Y-820172D01*
G01X28103D02*
X29983D01*
G01X33698Y-819332D02*
X34325Y-819857D01*
X35030Y-820172D01*
X35656D01*
X36283Y-819857D01*
X36753Y-819332D01*
X36988Y-818597D01*
X36831Y-817862D01*
X36440Y-817232D01*
X35735Y-816812D01*
X34795Y-816602D01*
X34246Y-816182D01*
X34011Y-815447D01*
X34168Y-814712D01*
X34560Y-814187D01*
X35108Y-813872D01*
X35656D01*
X36205Y-814082D01*
X36675Y-814607D01*
G01X39998Y-820172D02*
Y-813872D01*
G01X43288D02*
Y-820172D01*
G01Y-817022D02*
X39998D01*
G01X45985Y-820172D02*
X47943Y-813872D01*
X49901Y-820172D01*
G01X49196Y-817967D02*
X46690D01*
G01X52441Y-820172D02*
Y-813872D01*
X56045Y-820172D01*
Y-813872D01*
G01X65120Y-820172D02*
Y-813872D01*
X66686D01*
X67313Y-814187D01*
X67783Y-814607D01*
X68175Y-815237D01*
X68488Y-815972D01*
X68566Y-817022D01*
X68488Y-818072D01*
X68175Y-818807D01*
X67783Y-819437D01*
X67313Y-819857D01*
X66686Y-820172D01*
X65120D01*
G01X72203Y-813872D02*
X74083D01*
G01X73143D02*
Y-820172D01*
G01X72203D02*
X74083D01*
G01X77798Y-819332D02*
X78425Y-819857D01*
X79130Y-820172D01*
X79756D01*
X80383Y-819857D01*
X80853Y-819332D01*
X81088Y-818597D01*
X80931Y-817862D01*
X80540Y-817232D01*
X79835Y-816812D01*
X78895Y-816602D01*
X78346Y-816182D01*
X78111Y-815447D01*
X78268Y-814712D01*
X78660Y-814187D01*
X79208Y-813872D01*
X79756D01*
X80305Y-814082D01*
X80775Y-814607D01*
G01X85743Y-813872D02*
Y-820172D01*
G01X83941Y-813872D02*
X87545D01*
G01X92043Y-820382D02*
X91886Y-820277D01*
Y-820067D01*
X92043Y-819962D01*
X92200Y-820067D01*
Y-820277D01*
X92043Y-820382D01*
G01X98186Y-821327D02*
X98500Y-819962D01*
G01X104643Y-813872D02*
Y-820172D01*
G01X102841Y-813872D02*
X106445D01*
G01X108985Y-820172D02*
X110943Y-813872D01*
X112901Y-820172D01*
G01X112196Y-817967D02*
X109690D01*
G01X117243Y-820172D02*
X116616Y-820067D01*
X116068Y-819647D01*
X115598Y-819017D01*
X115285Y-818282D01*
X115128Y-817442D01*
Y-816602D01*
X115285Y-815762D01*
X115598Y-815027D01*
X116068Y-814397D01*
X116616Y-813977D01*
X117243Y-813872D01*
X117870Y-813977D01*
X118418Y-814397D01*
X118888Y-815027D01*
X119201Y-815762D01*
X119358Y-816602D01*
Y-817442D01*
X119201Y-818282D01*
X118888Y-819017D01*
X118418Y-819647D01*
X117870Y-820067D01*
X117243Y-820172D01*
G01X123543D02*
Y-817337D01*
X121976Y-813872D01*
G01X125110D02*
X123543Y-817337D01*
G01X128120Y-813872D02*
Y-818387D01*
X128433Y-819332D01*
X129060Y-819962D01*
X129843Y-820172D01*
X130626Y-819962D01*
X131253Y-819332D01*
X131566Y-818387D01*
Y-813872D01*
G01X134185Y-820172D02*
X136143Y-813872D01*
X138101Y-820172D01*
G01X137396Y-817967D02*
X134890D01*
G01X140641Y-820172D02*
Y-813872D01*
X144245Y-820172D01*
Y-813872D01*
G01X18166Y-824397D02*
X17696Y-824082D01*
X17148Y-823872D01*
X16521D01*
X15816Y-824187D01*
X15268Y-824712D01*
X14876Y-825342D01*
X14563Y-826392D01*
X14485Y-827337D01*
X14641Y-828282D01*
X14876Y-828912D01*
X15346Y-829542D01*
X15895Y-829962D01*
X16443Y-830172D01*
X16991D01*
X17540Y-829962D01*
X18010Y-829647D01*
X18401Y-829227D01*
G01X21803Y-823872D02*
X23683D01*
G01X22743D02*
Y-830172D01*
G01X21803D02*
X23683D01*
G01X29043Y-823872D02*
Y-830172D01*
G01X27241Y-823872D02*
X30845D01*
G01X35343Y-830172D02*
Y-827337D01*
X33776Y-823872D01*
G01X36910D02*
X35343Y-827337D01*
G01X46220Y-828912D02*
X46690Y-829647D01*
X47316Y-830067D01*
X48021Y-830172D01*
X48648Y-830067D01*
X49275Y-829542D01*
X49666Y-828912D01*
X49745Y-828282D01*
X49588Y-827547D01*
X49040Y-827022D01*
X48491Y-826812D01*
X47786D01*
G01X48491D02*
X48961Y-826497D01*
X49353Y-825972D01*
X49510Y-825342D01*
X49353Y-824712D01*
X48961Y-824187D01*
X48256Y-823872D01*
X47551Y-823977D01*
X46846Y-824397D01*
G01X52520Y-828912D02*
X52990Y-829647D01*
X53616Y-830067D01*
X54321Y-830172D01*
X54948Y-830067D01*
X55575Y-829542D01*
X55966Y-828912D01*
X56045Y-828282D01*
X55888Y-827547D01*
X55340Y-827022D01*
X54791Y-826812D01*
X54086D01*
G01X54791D02*
X55261Y-826497D01*
X55653Y-825972D01*
X55810Y-825342D01*
X55653Y-824712D01*
X55261Y-824187D01*
X54556Y-823872D01*
X53851Y-823977D01*
X53146Y-824397D01*
G01X58820Y-828912D02*
X59290Y-829647D01*
X59916Y-830067D01*
X60621Y-830172D01*
X61248Y-830067D01*
X61875Y-829542D01*
X62266Y-828912D01*
X62345Y-828282D01*
X62188Y-827547D01*
X61640Y-827022D01*
X61091Y-826812D01*
X60386D01*
G01X61091D02*
X61561Y-826497D01*
X61953Y-825972D01*
X62110Y-825342D01*
X61953Y-824712D01*
X61561Y-824187D01*
X60856Y-823872D01*
X60151Y-823977D01*
X59446Y-824397D01*
G01X66686Y-830172D02*
X66843Y-828807D01*
X67078Y-827652D01*
X67391Y-826602D01*
X67783Y-825447D01*
X68410Y-823872D01*
X65276D01*
G01X72986Y-830172D02*
X73143Y-828807D01*
X73378Y-827652D01*
X73691Y-826602D01*
X74083Y-825447D01*
X74710Y-823872D01*
X71576D01*
G01X79286Y-831327D02*
X79600Y-829962D01*
G01X85743Y-823872D02*
Y-830172D01*
G01X83941Y-823872D02*
X87545D01*
G01X90085Y-830172D02*
X92043Y-823872D01*
X94001Y-830172D01*
G01X93296Y-827967D02*
X90790D01*
G01X97403Y-823872D02*
X99283D01*
G01X98343D02*
Y-830172D01*
G01X97403D02*
X99283D01*
G01X102293Y-823872D02*
X103390Y-830172D01*
X104643Y-823872D01*
X105896Y-830172D01*
X106993Y-823872D01*
G01X108985Y-830172D02*
X110943Y-823872D01*
X112901Y-830172D01*
G01X112196Y-827967D02*
X109690D01*
G01X115441Y-830172D02*
Y-823872D01*
X119045Y-830172D01*
Y-823872D01*
G01X129451Y-832272D02*
X128668Y-831222D01*
X128276Y-830172D01*
Y-825972D01*
X128668Y-824922D01*
X129451Y-823872D01*
G01X140876Y-830172D02*
Y-823872D01*
X142835D01*
X143461Y-824187D01*
X143853Y-824607D01*
X144010Y-825447D01*
X143853Y-826287D01*
X143383Y-826812D01*
X142835Y-827127D01*
X140876D01*
G01X142835D02*
X144010Y-830172D01*
G01X148743Y-830382D02*
X148586Y-830277D01*
Y-830067D01*
X148743Y-829962D01*
X148900Y-830067D01*
Y-830277D01*
X148743Y-830382D01*
G01X155043Y-830172D02*
X154416Y-830067D01*
X153868Y-829647D01*
X153398Y-829017D01*
X153085Y-828282D01*
X152928Y-827442D01*
Y-826602D01*
X153085Y-825762D01*
X153398Y-825027D01*
X153868Y-824397D01*
X154416Y-823977D01*
X155043Y-823872D01*
X155670Y-823977D01*
X156218Y-824397D01*
X156688Y-825027D01*
X157001Y-825762D01*
X157158Y-826602D01*
Y-827442D01*
X157001Y-828282D01*
X156688Y-829017D01*
X156218Y-829647D01*
X155670Y-830067D01*
X155043Y-830172D01*
G01X161343Y-830382D02*
X161186Y-830277D01*
Y-830067D01*
X161343Y-829962D01*
X161500Y-830067D01*
Y-830277D01*
X161343Y-830382D01*
G01X169366Y-824397D02*
X168896Y-824082D01*
X168348Y-823872D01*
X167721D01*
X167016Y-824187D01*
X166468Y-824712D01*
X166076Y-825342D01*
X165763Y-826392D01*
X165685Y-827337D01*
X165841Y-828282D01*
X166076Y-828912D01*
X166546Y-829542D01*
X167095Y-829962D01*
X167643Y-830172D01*
X168191D01*
X168740Y-829962D01*
X169210Y-829647D01*
X169601Y-829227D01*
G01X173943Y-830382D02*
X173786Y-830277D01*
Y-830067D01*
X173943Y-829962D01*
X174100Y-830067D01*
Y-830277D01*
X173943Y-830382D01*
G01X180635Y-832272D02*
X181418Y-831222D01*
X181810Y-830172D01*
Y-825972D01*
X181418Y-824922D01*
X180635Y-823872D01*
G01X38743Y-799472D02*
X36223Y-799055D01*
X34018Y-797389D01*
X32128Y-794889D01*
X30868Y-791972D01*
X30238Y-788639D01*
Y-785305D01*
X30868Y-781972D01*
X32128Y-779055D01*
X34018Y-776556D01*
X36223Y-774889D01*
X38743Y-774472D01*
X41263Y-774889D01*
X43468Y-776556D01*
X45358Y-779055D01*
X46618Y-781972D01*
X47248Y-785305D01*
Y-788639D01*
X46618Y-791972D01*
X45358Y-794889D01*
X43468Y-797389D01*
X41263Y-799055D01*
X38743Y-799472D01*
G01X41263Y-792805D02*
X45043Y-799472D01*
G01X58588Y-782806D02*
Y-794472D01*
X59848Y-797389D01*
X61738Y-799055D01*
X63943Y-799472D01*
X66148Y-799055D01*
X68038Y-797389D01*
X69298Y-794472D01*
G01Y-799472D02*
Y-782806D01*
G01X94813Y-799472D02*
Y-782806D01*
G01Y-785722D02*
X93553Y-784056D01*
X91663Y-783222D01*
X89458Y-782806D01*
X87253Y-783639D01*
X85363Y-785305D01*
X84103Y-787806D01*
X83473Y-791139D01*
X84103Y-794472D01*
X85363Y-796973D01*
X87253Y-798639D01*
X89458Y-799472D01*
X91663Y-799055D01*
X93553Y-797806D01*
X94813Y-796139D01*
G01X108988Y-799472D02*
Y-782806D01*
G01Y-786972D02*
X110248Y-784889D01*
X112138Y-783222D01*
X114658Y-782806D01*
X116863Y-783222D01*
X118753Y-784889D01*
X119698Y-787806D01*
Y-799472D01*
G01X139543Y-774472D02*
Y-799472D01*
G01X135133Y-782806D02*
X143953D01*
G01X170413Y-799472D02*
Y-782806D01*
G01Y-785722D02*
X169153Y-784056D01*
X167263Y-783222D01*
X165058Y-782806D01*
X162853Y-783639D01*
X160963Y-785305D01*
X159703Y-787806D01*
X159073Y-791139D01*
X159703Y-794472D01*
X160963Y-796973D01*
X162853Y-798639D01*
X165058Y-799472D01*
X167263Y-799055D01*
X169153Y-797806D01*
X170413Y-796139D01*
G01X14641Y-810172D02*
Y-803872D01*
X18245Y-810172D01*
Y-803872D01*
G01X22743Y-810172D02*
X22116Y-810067D01*
X21568Y-809647D01*
X21098Y-809017D01*
X20785Y-808282D01*
X20628Y-807442D01*
Y-806602D01*
X20785Y-805762D01*
X21098Y-805027D01*
X21568Y-804397D01*
X22116Y-803977D01*
X22743Y-803872D01*
X23370Y-803977D01*
X23918Y-804397D01*
X24388Y-805027D01*
X24701Y-805762D01*
X24858Y-806602D01*
Y-807442D01*
X24701Y-808282D01*
X24388Y-809017D01*
X23918Y-809647D01*
X23370Y-810067D01*
X22743Y-810172D01*
G01X29043Y-810382D02*
X28886Y-810277D01*
Y-810067D01*
X29043Y-809962D01*
X29200Y-810067D01*
Y-810277D01*
X29043Y-810382D01*
G01X33855Y-804922D02*
X34325Y-804292D01*
X34873Y-803977D01*
X35500Y-803872D01*
X36283Y-804082D01*
X36831Y-804607D01*
X36988Y-805237D01*
X36910Y-805867D01*
X36596Y-806392D01*
X35030Y-807442D01*
X34325Y-808177D01*
X33855Y-809227D01*
X33698Y-810172D01*
X36988D01*
G01X41643D02*
Y-803872D01*
X40703Y-805132D01*
G01Y-810172D02*
X42583D01*
G01X47943D02*
Y-803872D01*
X47003Y-805132D01*
G01Y-810172D02*
X48883D01*
G01X54086Y-811327D02*
X54400Y-809962D01*
G01X58193Y-803872D02*
X59290Y-810172D01*
X60543Y-803872D01*
X61796Y-810172D01*
X62893Y-803872D01*
G01X68410Y-810172D02*
X65276D01*
Y-803872D01*
X68410D01*
G01X67156Y-806917D02*
X65276D01*
G01X71341Y-810172D02*
Y-803872D01*
X74945Y-810172D01*
Y-803872D01*
G01X77798Y-810172D02*
Y-803872D01*
G01X81088D02*
Y-810172D01*
G01Y-807022D02*
X77798D01*
G01X84020Y-803872D02*
Y-808387D01*
X84333Y-809332D01*
X84960Y-809962D01*
X85743Y-810172D01*
X86526Y-809962D01*
X87153Y-809332D01*
X87466Y-808387D01*
Y-803872D01*
G01X90085Y-810172D02*
X92043Y-803872D01*
X94001Y-810172D01*
G01X93296Y-807967D02*
X90790D01*
G01X103155Y-804922D02*
X103625Y-804292D01*
X104173Y-803977D01*
X104800Y-803872D01*
X105583Y-804082D01*
X106131Y-804607D01*
X106288Y-805237D01*
X106210Y-805867D01*
X105896Y-806392D01*
X104330Y-807442D01*
X103625Y-808177D01*
X103155Y-809227D01*
X102998Y-810172D01*
X106288D01*
G01X109141D02*
Y-803872D01*
X112745Y-810172D01*
Y-803872D01*
G01X115520Y-810172D02*
Y-803872D01*
X117086D01*
X117713Y-804187D01*
X118183Y-804607D01*
X118575Y-805237D01*
X118888Y-805972D01*
X118966Y-807022D01*
X118888Y-808072D01*
X118575Y-808807D01*
X118183Y-809437D01*
X117713Y-809857D01*
X117086Y-810172D01*
X115520D01*
G01X128276D02*
Y-803872D01*
X130235D01*
X130861Y-804187D01*
X131253Y-804607D01*
X131410Y-805447D01*
X131253Y-806287D01*
X130783Y-806812D01*
X130235Y-807127D01*
X128276D01*
G01X130235D02*
X131410Y-810172D01*
G01X134420D02*
Y-803872D01*
X135986D01*
X136613Y-804187D01*
X137083Y-804607D01*
X137475Y-805237D01*
X137788Y-805972D01*
X137866Y-807022D01*
X137788Y-808072D01*
X137475Y-808807D01*
X137083Y-809437D01*
X136613Y-809857D01*
X135986Y-810172D01*
X134420D01*
G01X142443Y-810382D02*
X142286Y-810277D01*
Y-810067D01*
X142443Y-809962D01*
X142600Y-810067D01*
Y-810277D01*
X142443Y-810382D01*
G01X210093Y-779172D02*
Y-787172D01*
X214093D01*
G01X221893D02*
Y-781839D01*
G01Y-782772D02*
X221493Y-782239D01*
X220893Y-781972D01*
X220193Y-781839D01*
X219493Y-782105D01*
X218893Y-782639D01*
X218493Y-783439D01*
X218293Y-784505D01*
X218493Y-785572D01*
X218893Y-786372D01*
X219493Y-786905D01*
X220193Y-787172D01*
X220893Y-787039D01*
X221493Y-786639D01*
X221893Y-786106D01*
G01X225993Y-789572D02*
X226593Y-789839D01*
X227393Y-789572D01*
X227893Y-789039D01*
X228293Y-788372D01*
X228893Y-786239D01*
X230193Y-781839D01*
G01X226993D02*
X228893Y-786239D01*
G01X234593Y-783572D02*
X237793D01*
X237493Y-782639D01*
X236993Y-782105D01*
X236293Y-781839D01*
X235593Y-781972D01*
X234993Y-782372D01*
X234593Y-783305D01*
X234393Y-784106D01*
Y-784905D01*
X234593Y-785705D01*
X235093Y-786505D01*
X235693Y-787039D01*
X236393Y-787172D01*
X237093Y-786905D01*
X237793Y-786106D01*
G01X242693Y-787172D02*
Y-781839D01*
G01Y-782905D02*
X243193Y-782372D01*
X243693Y-781972D01*
X244393Y-781839D01*
X244893Y-781972D01*
X245493Y-782372D01*
G01X229193Y-829172D02*
X232993D01*
X229193Y-837172D01*
X232993D01*
G01X239093Y-831839D02*
Y-837172D01*
G01Y-829705D02*
X238893Y-829572D01*
Y-829305D01*
X239093Y-829172D01*
X239293Y-829305D01*
Y-829572D01*
X239093Y-829705D01*
G01X245793Y-834505D02*
X248393D01*
G01X253093Y-837172D02*
Y-829172D01*
X255493D01*
X256293Y-829572D01*
X256893Y-830505D01*
X257093Y-831572D01*
X256893Y-832639D01*
X256393Y-833439D01*
X255493Y-833839D01*
X253093D01*
G01X263093Y-831839D02*
Y-837172D01*
G01Y-829705D02*
X262893Y-829572D01*
Y-829305D01*
X263093Y-829172D01*
X263293Y-829305D01*
Y-829572D01*
X263093Y-829705D01*
G01X269393Y-837172D02*
Y-831839D01*
G01Y-833172D02*
X269793Y-832505D01*
X270393Y-831972D01*
X271193Y-831839D01*
X271893Y-831972D01*
X272493Y-832505D01*
X272793Y-833439D01*
Y-837172D01*
G01X277693Y-839172D02*
X278393Y-839705D01*
X279193Y-839839D01*
X279893Y-839705D01*
X280493Y-839039D01*
X280893Y-838105D01*
Y-831839D01*
G01Y-832905D02*
X280493Y-832372D01*
X279893Y-831972D01*
X279193Y-831839D01*
X278393Y-832105D01*
X277893Y-832639D01*
X277493Y-833572D01*
X277293Y-834505D01*
X277393Y-835305D01*
X277793Y-836239D01*
X278393Y-836905D01*
X279193Y-837172D01*
X279793Y-837039D01*
X280493Y-836505D01*
X280893Y-835972D01*
G01X243593Y-804172D02*
Y-812172D01*
G01X241293Y-804172D02*
X245893D01*
G01X251593Y-812172D02*
X250793Y-812039D01*
X250093Y-811505D01*
X249493Y-810705D01*
X249093Y-809772D01*
X248893Y-808705D01*
Y-807639D01*
X249093Y-806572D01*
X249493Y-805639D01*
X250093Y-804839D01*
X250793Y-804305D01*
X251593Y-804172D01*
X252393Y-804305D01*
X253093Y-804839D01*
X253693Y-805639D01*
X254093Y-806572D01*
X254293Y-807639D01*
Y-808705D01*
X254093Y-809772D01*
X253693Y-810705D01*
X253093Y-811505D01*
X252393Y-812039D01*
X251593Y-812172D01*
G01X257593D02*
Y-804172D01*
X259993D01*
X260793Y-804572D01*
X261393Y-805505D01*
X261593Y-806572D01*
X261393Y-807639D01*
X260893Y-808439D01*
X259993Y-808839D01*
X257593D01*
G01X263593Y-787172D02*
Y-779172D01*
X262393Y-780772D01*
G01Y-787172D02*
X264793D01*
G01X336693Y-830505D02*
X337293Y-829705D01*
X337993Y-829305D01*
X338793Y-829172D01*
X339793Y-829439D01*
X340493Y-830105D01*
X340693Y-830905D01*
X340593Y-831706D01*
X340193Y-832372D01*
X338193Y-833705D01*
X337293Y-834639D01*
X336693Y-835972D01*
X336493Y-837172D01*
X340693D01*
G01X346593Y-829172D02*
X345793Y-829439D01*
X345193Y-830105D01*
X344793Y-830905D01*
X344493Y-831972D01*
X344393Y-833172D01*
X344493Y-834372D01*
X344793Y-835439D01*
X345193Y-836239D01*
X345793Y-836905D01*
X346593Y-837172D01*
X347393Y-836905D01*
X347993Y-836239D01*
X348393Y-835439D01*
X348693Y-834372D01*
X348793Y-833172D01*
X348693Y-831972D01*
X348393Y-830905D01*
X347993Y-830105D01*
X347393Y-829439D01*
X346593Y-829172D01*
G01X352693Y-830505D02*
X353293Y-829705D01*
X353993Y-829305D01*
X354793Y-829172D01*
X355793Y-829439D01*
X356493Y-830105D01*
X356693Y-830905D01*
X356593Y-831706D01*
X356193Y-832372D01*
X354193Y-833705D01*
X353293Y-834639D01*
X352693Y-835972D01*
X352493Y-837172D01*
X356693D01*
G01X360693Y-830505D02*
X361293Y-829705D01*
X361993Y-829305D01*
X362793Y-829172D01*
X363793Y-829439D01*
X364493Y-830105D01*
X364693Y-830905D01*
X364593Y-831706D01*
X364193Y-832372D01*
X362193Y-833705D01*
X361293Y-834639D01*
X360693Y-835972D01*
X360493Y-837172D01*
X364693D01*
G01X368793Y-837439D02*
X372393Y-829172D01*
G01X378593Y-837172D02*
Y-829172D01*
X377393Y-830772D01*
G01Y-837172D02*
X379793D01*
G01X384693Y-830505D02*
X385293Y-829705D01*
X385993Y-829305D01*
X386793Y-829172D01*
X387793Y-829439D01*
X388493Y-830105D01*
X388693Y-830905D01*
X388593Y-831706D01*
X388193Y-832372D01*
X386193Y-833705D01*
X385293Y-834639D01*
X384693Y-835972D01*
X384493Y-837172D01*
X388693D01*
G01X392793Y-837439D02*
X396393Y-829172D01*
G01X402593D02*
X401793Y-829439D01*
X401193Y-830105D01*
X400793Y-830905D01*
X400493Y-831972D01*
X400393Y-833172D01*
X400493Y-834372D01*
X400793Y-835439D01*
X401193Y-836239D01*
X401793Y-836905D01*
X402593Y-837172D01*
X403393Y-836905D01*
X403993Y-836239D01*
X404393Y-835439D01*
X404693Y-834372D01*
X404793Y-833172D01*
X404693Y-831972D01*
X404393Y-830905D01*
X403993Y-830105D01*
X403393Y-829439D01*
X402593Y-829172D01*
G01X408693Y-830505D02*
X409293Y-829705D01*
X409993Y-829305D01*
X410793Y-829172D01*
X411793Y-829439D01*
X412493Y-830105D01*
X412693Y-830905D01*
X412593Y-831706D01*
X412193Y-832372D01*
X410193Y-833705D01*
X409293Y-834639D01*
X408693Y-835972D01*
X408493Y-837172D01*
X412693D01*
G01X336393Y-814672D02*
Y-806672D01*
X338393D01*
X339193Y-807072D01*
X339793Y-807605D01*
X340293Y-808405D01*
X340693Y-809339D01*
X340793Y-810672D01*
X340693Y-812005D01*
X340293Y-812939D01*
X339793Y-813739D01*
X339193Y-814272D01*
X338393Y-814672D01*
X336393D01*
G01X344093D02*
X346593Y-806672D01*
X349093Y-814672D01*
G01X348193Y-811872D02*
X344993D01*
G01X354593Y-806672D02*
X353793Y-806939D01*
X353193Y-807605D01*
X352793Y-808405D01*
X352493Y-809472D01*
X352393Y-810672D01*
X352493Y-811872D01*
X352793Y-812939D01*
X353193Y-813739D01*
X353793Y-814405D01*
X354593Y-814672D01*
X355393Y-814405D01*
X355993Y-813739D01*
X356393Y-812939D01*
X356693Y-811872D01*
X356793Y-810672D01*
X356693Y-809472D01*
X356393Y-808405D01*
X355993Y-807605D01*
X355393Y-806939D01*
X354593Y-806672D01*
G01X360693Y-814672D02*
Y-806672D01*
X364493D01*
G01X363093Y-810539D02*
X360693D01*
G01X370593Y-806672D02*
X369793Y-806939D01*
X369193Y-807605D01*
X368793Y-808405D01*
X368493Y-809472D01*
X368393Y-810672D01*
X368493Y-811872D01*
X368793Y-812939D01*
X369193Y-813739D01*
X369793Y-814405D01*
X370593Y-814672D01*
X371393Y-814405D01*
X371993Y-813739D01*
X372393Y-812939D01*
X372693Y-811872D01*
X372793Y-810672D01*
X372693Y-809472D01*
X372393Y-808405D01*
X371993Y-807605D01*
X371393Y-806939D01*
X370593Y-806672D01*
G01X378593D02*
Y-814672D01*
G01X376293Y-806672D02*
X380893D01*
G01X384593Y-814672D02*
Y-806672D01*
X386993D01*
X387793Y-807072D01*
X388393Y-808005D01*
X388593Y-809072D01*
X388393Y-810139D01*
X387893Y-810939D01*
X386993Y-811339D01*
X384593D01*
G01X395393Y-810405D02*
X395793Y-810005D01*
X396093Y-809339D01*
X396293Y-808405D01*
X396093Y-807605D01*
X395693Y-807072D01*
X394993Y-806672D01*
X392293D01*
Y-814672D01*
X395593D01*
X396293Y-814139D01*
X396693Y-813339D01*
X396893Y-812405D01*
X396693Y-811472D01*
X396093Y-810672D01*
X395393Y-810405D01*
X392293D01*
G01X400093Y-814672D02*
X402593Y-806672D01*
X405093Y-814672D01*
G01X404193Y-811872D02*
X400993D01*
G01X408693Y-814672D02*
Y-806672D01*
X412493D01*
G01X411093Y-810539D02*
X408693D01*
G01X418593Y-806672D02*
X417793Y-806939D01*
X417193Y-807605D01*
X416793Y-808405D01*
X416493Y-809472D01*
X416393Y-810672D01*
X416493Y-811872D01*
X416793Y-812939D01*
X417193Y-813739D01*
X417793Y-814405D01*
X418593Y-814672D01*
X419393Y-814405D01*
X419993Y-813739D01*
X420393Y-812939D01*
X420693Y-811872D01*
X420793Y-810672D01*
X420693Y-809472D01*
X420393Y-808405D01*
X419993Y-807605D01*
X419393Y-806939D01*
X418593Y-806672D01*
G01X356693Y-787172D02*
Y-779172D01*
X360493D01*
G01X359093Y-783039D02*
X356693D01*
G01X366593Y-779172D02*
X365793Y-779439D01*
X365193Y-780105D01*
X364793Y-780905D01*
X364493Y-781972D01*
X364393Y-783172D01*
X364493Y-784372D01*
X364793Y-785439D01*
X365193Y-786239D01*
X365793Y-786905D01*
X366593Y-787172D01*
X367393Y-786905D01*
X367993Y-786239D01*
X368393Y-785439D01*
X368693Y-784372D01*
X368793Y-783172D01*
X368693Y-781972D01*
X368393Y-780905D01*
X367993Y-780105D01*
X367393Y-779439D01*
X366593Y-779172D01*
G01X374593D02*
Y-787172D01*
G01X372293Y-779172D02*
X376893D01*
G01X379593Y-789839D02*
X385593D01*
G01X388593Y-787172D02*
Y-779172D01*
X390993D01*
X391793Y-779572D01*
X392393Y-780505D01*
X392593Y-781572D01*
X392393Y-782639D01*
X391893Y-783439D01*
X390993Y-783839D01*
X388593D01*
G01X396393Y-787172D02*
Y-779172D01*
X398393D01*
X399193Y-779572D01*
X399793Y-780105D01*
X400293Y-780905D01*
X400693Y-781839D01*
X400793Y-783172D01*
X400693Y-784505D01*
X400293Y-785439D01*
X399793Y-786239D01*
X399193Y-786772D01*
X398393Y-787172D01*
X396393D01*
G01X407393Y-782905D02*
X407793Y-782505D01*
X408093Y-781839D01*
X408293Y-780905D01*
X408093Y-780105D01*
X407693Y-779572D01*
X406993Y-779172D01*
X404293D01*
Y-787172D01*
X407593D01*
X408293Y-786639D01*
X408693Y-785839D01*
X408893Y-784905D01*
X408693Y-783972D01*
X408093Y-783172D01*
X407393Y-782905D01*
X404293D01*
G01X411593Y-789839D02*
X417593D01*
G01X424793Y-779839D02*
X424193Y-779439D01*
X423493Y-779172D01*
X422693D01*
X421793Y-779572D01*
X421093Y-780239D01*
X420593Y-781039D01*
X420193Y-782372D01*
X420093Y-783572D01*
X420293Y-784772D01*
X420593Y-785572D01*
X421193Y-786372D01*
X421893Y-786905D01*
X422593Y-787172D01*
X423293D01*
X423993Y-786905D01*
X424593Y-786505D01*
X425093Y-785972D01*
G01X430593Y-787172D02*
X429793Y-787039D01*
X429093Y-786505D01*
X428493Y-785705D01*
X428093Y-784772D01*
X427893Y-783705D01*
Y-782639D01*
X428093Y-781572D01*
X428493Y-780639D01*
X429093Y-779839D01*
X429793Y-779305D01*
X430593Y-779172D01*
X431393Y-779305D01*
X432093Y-779839D01*
X432693Y-780639D01*
X433093Y-781572D01*
X433293Y-782639D01*
Y-783705D01*
X433093Y-784772D01*
X432693Y-785705D01*
X432093Y-786505D01*
X431393Y-787039D01*
X430593Y-787172D01*
G01X436293D02*
Y-779172D01*
X440893Y-787172D01*
Y-779172D01*
G01X444093D02*
X446593Y-787172D01*
X449093Y-779172D01*
G01X456593Y-787172D02*
X452593D01*
Y-779172D01*
X456593D01*
G01X454993Y-783039D02*
X452593D01*
G01X460593Y-787172D02*
Y-779172D01*
X463093D01*
X463893Y-779572D01*
X464393Y-780105D01*
X464593Y-781172D01*
X464393Y-782239D01*
X463793Y-782905D01*
X463093Y-783305D01*
X460593D01*
G01X463093D02*
X464593Y-787172D01*
G01X470593Y-779172D02*
Y-787172D01*
G01X468293Y-779172D02*
X472893D01*
G01X480593Y-787172D02*
X476593D01*
Y-779172D01*
X480593D01*
G01X478993Y-783039D02*
X476593D01*
G01X484593Y-787172D02*
Y-779172D01*
X487093D01*
X487893Y-779572D01*
X488393Y-780105D01*
X488593Y-781172D01*
X488393Y-782239D01*
X487793Y-782905D01*
X487093Y-783305D01*
X484593D01*
G01X487093D02*
X488593Y-787172D01*
G01X425093Y-840172D02*
Y-832172D01*
X423893Y-833772D01*
G01Y-840172D02*
X426293D01*
G01X431193Y-836839D02*
X431893Y-835905D01*
X432493Y-835372D01*
X433293Y-835105D01*
X433993Y-835372D01*
X434493Y-835905D01*
X434893Y-836705D01*
X434993Y-837639D01*
X434893Y-838439D01*
X434493Y-839239D01*
X433893Y-839905D01*
X433193Y-840172D01*
X432393Y-839905D01*
X431693Y-839106D01*
X431293Y-837905D01*
X431193Y-836572D01*
X431393Y-834839D01*
X431693Y-833905D01*
X432193Y-832972D01*
X432893Y-832305D01*
X433593Y-832172D01*
X434293Y-832439D01*
X434793Y-833105D01*
G01X441093Y-840439D02*
X440893Y-840305D01*
Y-840039D01*
X441093Y-839905D01*
X441293Y-840039D01*
Y-840305D01*
X441093Y-840439D01*
G01X447193Y-836839D02*
X447893Y-835905D01*
X448493Y-835372D01*
X449293Y-835105D01*
X449993Y-835372D01*
X450493Y-835905D01*
X450893Y-836705D01*
X450993Y-837639D01*
X450893Y-838439D01*
X450493Y-839239D01*
X449893Y-839905D01*
X449193Y-840172D01*
X448393Y-839905D01*
X447693Y-839106D01*
X447293Y-837905D01*
X447193Y-836572D01*
X447393Y-834839D01*
X447693Y-833905D01*
X448193Y-832972D01*
X448893Y-832305D01*
X449593Y-832172D01*
X450293Y-832439D01*
X450793Y-833105D01*
G01X470093Y-840172D02*
Y-832172D01*
X468893Y-833772D01*
G01Y-840172D02*
X471293D01*
G01X477893D02*
X478093Y-838439D01*
X478393Y-836972D01*
X478793Y-835639D01*
X479293Y-834172D01*
X480093Y-832172D01*
X476093D01*
G01X486093Y-840439D02*
X485893Y-840305D01*
Y-840039D01*
X486093Y-839905D01*
X486293Y-840039D01*
Y-840305D01*
X486093Y-840439D01*
G01X492193Y-833505D02*
X492793Y-832705D01*
X493493Y-832305D01*
X494293Y-832172D01*
X495293Y-832439D01*
X495993Y-833105D01*
X496193Y-833905D01*
X496093Y-834706D01*
X495693Y-835372D01*
X493693Y-836705D01*
X492793Y-837639D01*
X492193Y-838972D01*
X491993Y-840172D01*
X496193D01*
G01X490193Y-815172D02*
Y-807172D01*
X493993D01*
G01X492593Y-811039D02*
X490193D01*
G54D23*
X152200Y241200D03*
Y235400D03*
X147000Y241200D03*
Y235400D03*
X1064500Y276242D03*
Y270442D03*
Y323742D03*
Y317942D03*
Y359642D03*
Y365442D03*
Y418742D03*
Y412942D03*
Y466242D03*
Y460442D03*
Y513742D03*
Y507942D03*
G54D32*
X170040Y245314D03*
X710000Y41984D03*
X706000Y59484D03*
X803500Y264984D03*
X792354Y265093D03*
X782354D03*
X1041500Y188984D03*
X1091000Y96984D03*
X1095100D03*
X1108500Y141984D03*
X1110000Y195484D03*
X1118000D03*
X1106000D03*
X1114000D03*
X1122000D03*
X1133000D03*
G54D14*
X19922Y214173D03*
Y367716D03*
G54D41*
X165539Y539000D03*
X213539D03*
X261539D03*
X323019D03*
X371019D03*
X419019D03*
X480500D03*
X528500D03*
X576500D03*
X637981D03*
X685981D03*
X733981D03*
G54D50*
X268000Y240000D03*
X312500D03*
X357000D03*
X428500D03*
X472500D03*
X516500D03*
X578500D03*
X622500D03*
X666500D03*
X735981D03*
X779981D03*
X823981D03*
G54D108*
G01X141840Y234905D02*
Y239397D01*
X141664Y239573D01*
G54D24*
X178356Y216830D03*
X687016Y36500D03*
Y32500D03*
X698616Y57800D03*
X1019516Y98000D03*
Y118000D03*
X1041070Y131267D03*
Y139267D03*
Y135267D03*
X1048070Y131267D03*
X1096516Y188000D03*
X1093016Y173500D03*
X1096516Y179500D03*
X1096484Y183599D03*
X1123016Y138457D03*
X1177927Y346750D03*
X1178016Y489250D03*
G54D60*
X699016Y53009D03*
G54D33*
X170040Y242347D03*
X710000Y39017D03*
X706000Y56517D03*
X803500Y262017D03*
X792354Y262126D03*
X782354D03*
X1041500Y186017D03*
X1091000Y94017D03*
X1095100D03*
X1108500Y139017D03*
X1110000Y192517D03*
X1118000D03*
X1106000D03*
X1114000D03*
X1122000D03*
X1133000D03*
G54D51*
X253819Y477204D03*
X411299D03*
X568780D03*
X726261D03*
G54D15*
X38780Y232598D03*
Y239291D03*
Y252598D03*
Y259291D03*
Y272598D03*
Y279291D03*
Y292598D03*
Y299291D03*
X48780Y232598D03*
Y239291D03*
Y252598D03*
Y259291D03*
Y272598D03*
Y279291D03*
Y292598D03*
Y299291D03*
G54D42*
X185224Y539000D03*
X233224D03*
X281224D03*
X342704D03*
X390704D03*
X438704D03*
X500185D03*
X548185D03*
X596185D03*
X657666D03*
X705666D03*
X753666D03*
G54D109*
G01X172934Y219110D02*
X171750Y220294D01*
X169612D01*
G01X181415Y216830D02*
X183900D01*
G01X178265Y213443D02*
Y216830D01*
G01D02*
X177687D01*
X176927Y216070D01*
X173325D01*
X171069Y218326D01*
X169513D01*
G01X169612Y224232D02*
X173674D01*
X174909Y222997D01*
Y219842D01*
X175976Y218775D01*
G01X178265Y220830D02*
Y219654D01*
X177386Y218775D01*
X175976D01*
G01X169612Y222263D02*
X172712D01*
G01X166068Y235649D02*
Y238749D01*
G01X166040Y242255D02*
Y238777D01*
X166068Y238749D01*
G01X178265Y231330D02*
X175103Y228168D01*
X173869D01*
G01D02*
X169612D01*
G01X178325Y224820D02*
X177962Y225183D01*
X175481D01*
G01D02*
X174464Y226200D01*
X169612D01*
G01X170040Y242255D02*
X172106D01*
X172624Y242773D01*
Y250673D01*
X171374Y251923D01*
G01X162132Y241140D02*
Y239879D01*
X160017Y237764D01*
G01D02*
X161545D01*
X162132Y237177D01*
Y235649D01*
G01Y249140D02*
Y245160D01*
G01D02*
Y241140D01*
G01X645575Y33000D02*
X647999D01*
G01D02*
X651499Y29500D01*
X687075D01*
X690075Y32500D01*
G01X696260Y43363D02*
X695363D01*
X694500Y42500D01*
Y40500D01*
X692500Y38500D01*
Y38445D01*
X692420Y38365D01*
Y34945D01*
X690075Y32600D01*
Y32500D01*
G01Y36500D02*
Y39500D01*
G01D02*
X691500Y40925D01*
Y42500D01*
X694332Y45332D01*
X696654D01*
G01X703346D02*
X705399D01*
X706080Y44651D01*
Y40686D01*
X707000Y39766D01*
Y32000D01*
G01D02*
X704575D01*
G01X703346Y47300D02*
X706200D01*
X708000Y45500D01*
Y40925D01*
X710000Y38925D01*
G01X782354Y265184D02*
X784855D01*
G01D02*
X787354D01*
G01X792354Y262034D02*
Y260594D01*
X791372Y259612D01*
X790000D01*
G01D02*
X788102D01*
X787354Y260360D01*
Y262034D01*
G01X792354Y265184D02*
Y265299D01*
X793034Y265979D01*
X794900D01*
G01D02*
X797854D01*
G01X803500Y265075D02*
X806000D01*
G01X786500Y316700D02*
Y305500D01*
X806500Y285500D01*
G01X814500Y293000D02*
X793800Y313700D01*
Y323880D01*
G01X1082833Y630687D02*
X788080D01*
X787400Y631367D01*
Y640007D01*
X788080Y640687D01*
X1082833D01*
G01X806000Y265075D02*
X806465D01*
X807260Y265870D01*
X809500D01*
G01X808425Y334000D02*
Y323575D01*
X821000Y311000D01*
Y270525D01*
G01X816000D02*
X818500Y273025D01*
Y306000D01*
X806000Y318500D01*
Y341575D01*
X808425Y344000D01*
G01X814050Y341450D02*
X818000Y337500D01*
X820201D01*
G01X832799D02*
X840000D01*
G01D02*
Y336000D01*
X834370Y330370D01*
Y329000D01*
G01X832799Y368600D02*
X838399Y363000D01*
X840000D01*
G01X813100Y368600D02*
Y365901D01*
X818401Y360600D01*
X820201D01*
G01X832799Y345500D02*
X840000D01*
G01D02*
Y355499D01*
X834899Y360600D01*
X832799D01*
G01X820201Y345500D02*
X818100D01*
X814050Y341450D01*
G01X820201Y368600D02*
X813100D01*
G01X909000Y283475D02*
X906025Y280500D01*
X873300D01*
X858600Y295200D01*
Y321400D01*
X848500Y331500D01*
Y335800D01*
G01X840000Y363000D02*
Y369701D01*
G01X940000Y283800D02*
X944000D01*
X951000Y290800D01*
Y307556D01*
X943171Y315385D01*
G01X1011000Y98000D02*
X1019425D01*
G01Y118000D02*
X1011000D01*
G01X1022575Y98000D02*
Y100925D01*
G01Y118000D02*
X1022483Y117908D01*
Y116176D01*
X1022575Y116084D01*
Y115500D01*
G01X1034500Y145000D02*
Y147000D01*
X1035601Y148101D01*
Y149381D01*
G01X1037000Y146300D02*
X1037570Y146870D01*
Y149381D01*
G01X1037500Y142000D02*
Y143500D01*
X1039538Y145538D01*
Y149381D01*
G01X1039016Y183027D02*
X1037570Y181581D01*
Y176153D01*
G01X1039538D02*
Y179208D01*
G01X1049356Y143900D02*
X1049338Y143908D01*
X1047412Y148563D01*
Y149381D01*
G01X1047159Y141487D02*
Y144176D01*
X1045444Y148317D01*
Y149381D01*
G01X1054500Y148500D02*
Y151000D01*
X1053560Y151940D01*
X1052040D01*
G01X1064500Y166000D02*
X1073274Y157226D01*
Y150749D01*
G01X1044129Y139267D02*
X1047308D01*
X1048000Y138575D01*
G01D02*
X1053505Y144080D01*
G01D02*
X1056500Y147075D01*
Y152500D01*
X1055091Y153909D01*
X1051940D01*
G01Y155877D02*
X1057500D01*
G01X1048000Y135425D02*
X1049424D01*
X1050499Y136500D01*
X1053000D01*
G01X1044129Y135267D02*
X1047842D01*
X1048000Y135425D01*
G01X1053000Y136500D02*
Y135001D01*
X1051129Y133130D01*
Y131267D01*
G01X1070715Y150749D02*
Y146500D01*
G01X1051940Y161783D02*
X1065118D01*
X1070715Y156186D01*
Y150749D01*
G01X1051940Y159814D02*
X1063500D01*
G01X1051940Y163751D02*
X1059751D01*
X1060500Y164500D01*
G01D02*
X1062000Y166000D01*
X1064500D01*
G01X1059500Y175500D02*
Y181001D01*
X1058000Y182501D01*
Y185925D01*
G01X1059500Y175500D02*
Y173500D01*
X1055657Y169657D01*
X1051940D01*
G01X1053500Y185925D02*
Y181500D01*
X1054000Y181000D01*
G01X1051940Y171625D02*
X1054125D01*
X1056500Y174000D01*
Y178500D01*
X1054000Y181000D01*
G01X1067000Y185925D02*
X1072021D01*
X1078393Y179553D01*
Y174785D01*
G01X1067000Y185925D02*
Y176500D01*
X1066000Y175500D01*
G01D02*
Y173000D01*
X1058720Y165720D01*
X1051940D01*
G01X1062500Y181000D02*
Y185925D01*
G01X1051940Y167688D02*
X1057188D01*
X1062500Y173000D01*
Y181000D01*
G01Y189075D02*
Y191500D01*
G01X1058000Y189075D02*
X1053500D01*
G01X1058000D02*
Y191500D01*
G01X1087000Y100000D02*
X1086425Y100575D01*
Y103000D01*
G01X1100276Y101240D02*
X1098516Y103000D01*
X1094500D01*
G01D02*
X1089575D01*
G01X1106500Y155000D02*
X1105200Y153700D01*
Y152100D01*
X1100600Y147500D01*
X1100075D01*
G01X1100107Y143144D02*
X1101444D01*
X1102900Y144600D01*
Y145400D01*
X1105000Y147500D01*
G01X1100043Y156099D02*
Y160413D01*
G01D02*
X1101409Y161779D01*
X1105500D01*
G01X1082000Y143600D02*
Y157001D01*
X1075834Y163167D01*
Y174785D01*
G01X1092000Y159500D02*
X1092913Y160413D01*
X1096893D01*
G01X1096925Y147500D02*
Y143176D01*
X1096957Y143144D01*
G01X1100043Y151856D02*
Y150780D01*
X1096925Y147662D01*
Y147500D01*
G01X1096957Y143144D02*
X1094500D01*
G01X1084401Y159260D02*
X1088882Y154779D01*
Y140229D01*
X1089566Y139545D01*
X1089772D01*
G01X1096075Y173500D02*
X1100425D01*
G01D02*
Y174924D01*
X1101501Y176000D01*
X1108500D01*
G01X1109724Y97500D02*
X1115500D01*
G01D02*
X1127000D01*
X1129000Y99500D01*
X1161900D01*
X1171000Y90400D01*
G01X1109724Y93760D02*
Y88201D01*
X1109925Y88000D01*
G01X1109724Y93760D02*
X1120260D01*
X1121000Y94500D01*
G01X1109925Y88000D02*
X1110100Y87825D01*
Y83000D01*
G01D02*
X1107660D01*
X1107160Y82500D01*
X1103740D01*
G01X1151000Y90400D02*
X1146900Y94500D01*
X1121000D01*
G01X1129743Y142556D02*
Y149225D01*
X1129118Y149850D01*
Y153119D01*
G01X1132941Y131996D02*
X1130125Y134812D01*
Y135940D01*
G01D02*
Y138457D01*
G01X1129743Y142556D02*
Y138839D01*
X1130125Y138457D01*
G01X1127148Y153119D02*
Y147566D01*
G01D02*
Y144843D01*
X1126593Y144288D01*
Y142556D01*
G01X1123441Y131996D02*
X1126075Y134630D01*
Y135973D01*
G01D02*
Y138457D01*
G01X1126593Y142556D02*
Y139000D01*
X1126075Y138482D01*
Y138457D01*
G01X1118000Y146000D02*
X1119268Y147268D01*
Y153119D01*
G01X1112500Y142075D02*
X1114075D01*
X1118000Y146000D01*
G01X1108500Y142075D02*
X1112500D01*
G01X1116518Y159809D02*
X1111309D01*
X1106500Y155000D01*
G01X1121238Y153119D02*
Y144500D01*
G01X1116518Y157839D02*
X1113339D01*
X1108500Y153000D01*
Y151000D01*
X1105000Y147500D01*
G01X1112500Y151000D02*
Y153500D01*
X1114869Y155869D01*
X1116518D01*
G01X1104500Y142075D02*
X1104584D01*
X1106078Y143569D01*
Y144578D01*
X1112500Y151000D01*
G01Y138925D02*
X1115425D01*
G01X1119000Y189500D02*
Y187001D01*
X1123208Y182793D01*
Y180279D01*
G01X1116518Y163749D02*
X1111100D01*
G01X1110925Y187500D02*
X1106000Y192425D01*
G01X1119268Y180279D02*
Y180585D01*
X1114353Y185500D01*
X1112925D01*
X1110925Y187500D01*
G01X1125178Y180279D02*
Y183822D01*
X1123500Y185500D01*
Y187000D01*
G01D02*
X1122500Y188000D01*
Y191925D01*
X1122000Y192425D01*
G01X1116518Y171619D02*
X1113368D01*
G01X1110800Y170000D02*
X1112199D01*
X1112550Y169649D01*
X1116518D01*
G01X1113129Y165719D02*
X1116518D01*
G01X1131088Y186912D02*
X1133000Y188824D01*
Y192425D01*
G01X1108500Y176000D02*
X1113001D01*
X1113442Y175559D01*
X1116518D01*
G01X1121238Y180279D02*
Y181810D01*
X1114500Y188548D01*
Y188700D01*
G01D02*
X1114000Y189200D01*
Y192425D01*
G01X1105500Y161779D02*
X1116518D01*
G01Y167679D02*
X1112378D01*
X1111999Y167300D01*
X1109321D01*
X1108821Y166800D01*
G01X1118000Y192425D02*
X1122000D01*
G01X1110000D02*
X1114000D01*
G01X1158200Y137700D02*
Y137291D01*
X1152587Y131678D01*
G01Y139158D02*
X1153158D01*
X1158750Y144750D01*
G01D02*
X1157587Y145913D01*
X1151585D01*
G01X1147618Y165719D02*
X1152781D01*
G01X1131088Y180279D02*
Y186912D01*
G01X1170600Y105500D02*
Y103260D01*
X1171000Y102860D01*
Y90400D01*
G01X1166000Y140760D02*
Y117425D01*
X1171925Y111500D01*
G01X1170600Y105500D02*
Y110175D01*
X1171925Y111500D01*
G54D34*
X166040Y242346D03*
X710000Y46516D03*
X787354Y262125D03*
X1048000Y135516D03*
X1067000Y186016D03*
X1053500D03*
X1058000D03*
X1062500D03*
X1104500Y139016D03*
X1112500D03*
G54D25*
X181323Y216830D03*
X689983Y36500D03*
Y32500D03*
X701583Y57800D03*
X1022483Y98000D03*
Y118000D03*
X1044037Y131267D03*
X1051037D03*
X1044037Y139267D03*
Y135267D03*
X1099483Y188000D03*
X1095983Y173500D03*
X1099483Y179500D03*
X1099451Y183599D03*
X1125983Y138457D03*
X1180894Y346750D03*
X1180983Y489250D03*
G54D70*
X797854Y262239D03*
Y265979D03*
X809500Y262130D03*
Y265870D03*
G54D61*
X700984Y53009D03*
G54D43*
X201000Y20500D03*
X892110Y81122D03*
X1176815Y555392D03*
G54D52*
X296752Y129685D03*
Y139685D03*
Y149685D03*
X331752Y129685D03*
X306752D03*
X331752Y139685D03*
Y149685D03*
Y159685D03*
X306752Y139685D03*
Y149685D03*
Y159685D03*
X341752Y129685D03*
Y139685D03*
Y149685D03*
Y159685D03*
X376752Y129685D03*
X366752D03*
X376752Y139685D03*
Y149685D03*
Y159685D03*
X366752Y139685D03*
Y149685D03*
Y159685D03*
X411752Y129685D03*
X401752D03*
X411752Y139685D03*
Y149685D03*
Y159685D03*
X401752Y139685D03*
Y149685D03*
Y159685D03*
X446752Y129685D03*
X436752D03*
X446752Y139685D03*
Y149685D03*
Y159685D03*
X436752Y139685D03*
Y149685D03*
Y159685D03*
X481752Y129685D03*
X471752D03*
X481752Y139685D03*
Y149685D03*
Y159685D03*
X471752Y139685D03*
Y149685D03*
Y159685D03*
X712559Y129408D03*
Y119408D03*
Y149408D03*
Y139408D03*
X722559Y129408D03*
Y119408D03*
X747559Y129408D03*
Y119408D03*
X722559Y149408D03*
Y139408D03*
X747559Y149408D03*
Y139408D03*
X757559Y129408D03*
Y119408D03*
Y149408D03*
Y139408D03*
X782559Y129408D03*
Y119408D03*
X792559Y129408D03*
Y119408D03*
X782559Y149408D03*
Y139408D03*
X792559Y149408D03*
Y139408D03*
X812559Y119408D03*
Y129408D03*
X822559Y119408D03*
Y129408D03*
X832559Y119408D03*
Y129408D03*
X812559Y139408D03*
Y149408D03*
X822559Y139408D03*
Y149408D03*
X832559Y139408D03*
X852559Y129408D03*
Y119408D03*
X862559Y129408D03*
Y119408D03*
X852559Y149408D03*
Y139408D03*
X862559Y149408D03*
Y139408D03*
X887559Y129408D03*
Y119408D03*
Y149408D03*
Y139408D03*
X897559Y129408D03*
Y119408D03*
X922559Y129408D03*
Y119408D03*
X897559Y149408D03*
Y139408D03*
X922559Y149408D03*
Y139408D03*
X932559Y129408D03*
Y119408D03*
Y149408D03*
Y139408D03*
X1226024Y221929D03*
X1236024D03*
X1246024D03*
X1226024Y231929D03*
X1236024D03*
X1246024D03*
X1226024Y256929D03*
X1236024D03*
X1246024D03*
X1226024Y266929D03*
X1236024D03*
X1246024D03*
X1236024Y286929D03*
X1246024D03*
X1226024Y306929D03*
X1236024D03*
X1246024D03*
X1226024Y316929D03*
X1236024D03*
X1246024D03*
X1226024Y341929D03*
X1236024D03*
X1246024D03*
X1226024Y351929D03*
X1236024D03*
X1246024D03*
X1256024Y221929D03*
Y231929D03*
Y256929D03*
Y266929D03*
Y286929D03*
Y306929D03*
Y316929D03*
Y341929D03*
Y351929D03*
G54D16*
X33780Y334724D03*
Y324724D03*
X38780Y319724D03*
Y329724D03*
Y339724D03*
X33780Y344724D03*
X38780Y349724D03*
X48780Y319724D03*
Y329724D03*
Y339724D03*
X43780Y314724D03*
Y324724D03*
Y334724D03*
X48780Y349724D03*
X43780Y344724D03*
G54D26*
X164101Y216997D03*
G54D35*
X166040Y245313D03*
X710000Y49483D03*
X787354Y265092D03*
X1048000Y138483D03*
X1067000Y188983D03*
X1053500D03*
X1058000D03*
X1062500D03*
X1104500Y141983D03*
X1112500D03*
G54D44*
X197400Y214054D03*
Y233346D03*
G54D71*
X807315Y424566D03*
Y467144D03*
X863917Y424566D03*
Y467144D03*
G54D80*
X1027727Y149281D03*
Y176253D03*
X1049381Y149281D03*
Y176253D03*
G54D62*
X703346Y49268D03*
Y45332D03*
Y47300D03*
X696654Y45332D03*
Y49268D03*
G54D53*
X296752Y159685D03*
X832559Y149408D03*
X1226024Y286929D03*
G54D17*
X33780Y314724D03*
G54D63*
X703740Y51237D03*
G54D18*
X60630Y99724D03*
Y482205D03*
X108858Y99724D03*
Y482205D03*
G54D72*
X832799Y337500D03*
X820201D03*
Y368600D03*
X832799D03*
Y360600D03*
X820201D03*
Y345500D03*
X832799D03*
G54D36*
X162132Y249140D03*
X158982D03*
X162132Y245160D03*
X158982D03*
X239575Y243000D03*
X236425D03*
X239575Y247500D03*
X236425D03*
X395575Y242500D03*
X392425D03*
X395575Y247000D03*
X392425D03*
X549075Y243500D03*
X545925D03*
X549075Y248000D03*
X545925D03*
X645575Y33000D03*
X642425D03*
X645575Y37000D03*
X642425D03*
X706556Y243500D03*
X703406D03*
X706556Y248000D03*
X703406D03*
X1108590Y224241D03*
X1111740D03*
D03*
X1114890D03*
X1111656Y231741D03*
X1114806D03*
X1111656D03*
X1108506D03*
G54D81*
X1025068Y151940D03*
Y173594D03*
X1052040Y151940D03*
Y173594D03*
G54D54*
X293500Y204500D03*
X286500D03*
X293500Y196500D03*
X286500D03*
X329500Y204500D03*
Y196500D03*
X315000Y204500D03*
X308000D03*
X315000Y196500D03*
X308000D03*
X358000Y204500D03*
X351000D03*
X358000Y196500D03*
X351000D03*
X336500Y204500D03*
Y196500D03*
X379500Y204500D03*
X372500D03*
X379500Y197000D03*
X372500D03*
X422500Y204500D03*
X415500D03*
X422500Y197000D03*
X415500D03*
X401000Y204500D03*
X394000D03*
X401000Y197000D03*
X394000D03*
X594000Y204000D03*
Y196500D03*
X622500D03*
X615500D03*
X622500Y204000D03*
X615500D03*
X601000D03*
Y196500D03*
X658500Y204000D03*
Y196500D03*
X644000Y204000D03*
X637000D03*
X644000Y196500D03*
X637000D03*
X687000Y204000D03*
X680000D03*
X687000Y196500D03*
X680000D03*
X665500Y204000D03*
Y196500D03*
X708490Y204000D03*
X701490D03*
X708490Y196500D03*
X701490D03*
X729990Y204000D03*
X722990D03*
X729990Y196500D03*
X722990D03*
X758000Y43000D03*
X751000D03*
X758000Y34500D03*
X751000D03*
X758000Y60000D03*
X751000D03*
X758000Y51500D03*
X751000D03*
X1144585Y145913D03*
X1151585D03*
G54D27*
X158588Y218326D03*
Y220294D03*
Y222263D03*
Y224232D03*
Y226200D03*
Y228168D03*
Y230137D03*
Y232106D03*
Y234074D03*
X169612D03*
Y232106D03*
Y230137D03*
Y228168D03*
Y226200D03*
Y224232D03*
Y222263D03*
Y220294D03*
G54D90*
X1124598Y166699D03*
G54D45*
X208071Y267204D03*
X200197D03*
X215945D03*
X231693D03*
X223819D03*
X239567D03*
X247441D03*
X357677D03*
X365551D03*
X373425D03*
X389173D03*
X381299D03*
X404921D03*
X397047D03*
X523032D03*
X515158D03*
X530906D03*
X538780D03*
X546654D03*
X562402D03*
X554528D03*
X680513D03*
X672639D03*
X688387D03*
X704135D03*
X696261D03*
X712009D03*
X719883D03*
G54D28*
X169513Y218326D03*
G54D64*
X703740Y43363D03*
G36*
G01X82800Y111574D02*
G02X82795Y87873I-5J-11850D01*
G02X82790Y111574I0J11851D01*
G01Y109524D01*
G03X82795Y89923I5J-9800D01*
G03X82800Y109524I0J9801D01*
G01Y111574D01*
G37*
G36*
G01Y494055D02*
G02X82795Y470354I-5J-11850D01*
G02X82790Y494055I0J11851D01*
G01Y492005D01*
G03X82795Y472404I5J-9800D01*
G03X82800Y492005I0J9801D01*
G01Y494055D01*
G37*
G54D73*
X830630Y329000D03*
X834370D03*
G54D55*
X653700Y52700D03*
Y45700D03*
X677400Y52700D03*
Y45700D03*
X685300Y52700D03*
Y45700D03*
X669500Y52700D03*
Y45700D03*
X661600Y52700D03*
Y45700D03*
X1130368Y228060D03*
X1121568Y224060D03*
Y232060D03*
G54D37*
X164100Y232499D03*
Y228956D03*
Y225413D03*
Y221869D03*
G54D82*
X1041507Y149381D03*
X1039538D03*
X1037570D03*
X1035601D03*
Y176153D03*
X1037570D03*
X1039538D03*
X1041507D03*
X1047412Y149381D03*
X1045444D03*
X1043475D03*
Y176153D03*
X1045444D03*
X1047412D03*
G54D91*
X1116518Y159809D03*
Y157839D03*
Y155869D03*
Y177529D03*
Y175559D03*
Y173589D03*
Y171619D03*
Y169649D03*
Y167679D03*
Y165719D03*
Y163749D03*
Y161779D03*
X1147618Y155869D03*
Y157839D03*
Y159809D03*
Y161779D03*
Y163749D03*
Y165719D03*
Y167679D03*
Y169649D03*
Y171619D03*
Y173589D03*
Y175559D03*
Y177529D03*
G54D46*
X193819Y477204D03*
X223819D03*
X351299D03*
X381299D03*
X508780D03*
X538780D03*
X666261D03*
X696261D03*
G54D56*
X641300Y45200D03*
X647100D03*
X1039100Y126500D03*
X1044900D03*
X1101400Y168500D03*
X1095600D03*
X1110100Y83000D03*
X1115900D03*
X1151535Y124913D03*
X1170600Y105500D03*
X1176400D03*
X1174311Y328750D03*
X1168511D03*
X1184511D03*
X1190311D03*
Y335750D03*
X1184511D03*
X1168511D03*
X1174311D03*
Y341750D03*
X1168511D03*
X1184511D03*
X1190311D03*
X1184600Y484250D03*
X1190400D03*
X1174400D03*
X1168600D03*
X1174400Y471250D03*
X1168600D03*
X1184600D03*
X1190400D03*
X1174400Y478250D03*
X1168600D03*
X1184600D03*
X1190400D03*
G54D74*
X840000Y369701D03*
Y382299D03*
X1155000Y193201D03*
Y205799D03*
G54D38*
X162132Y235649D03*
X166068D03*
G54D92*
X1119268Y153119D03*
X1121238D03*
X1123208D03*
X1125178D03*
X1127148D03*
X1129118D03*
X1131088D03*
Y180279D03*
X1129118D03*
X1127148D03*
X1125178D03*
X1123208D03*
X1121238D03*
X1119268D03*
X1136988Y153119D03*
X1138958D03*
X1140928D03*
X1142898D03*
X1144868D03*
Y180279D03*
X1142898D03*
X1140928D03*
X1138958D03*
X1136988D03*
G54D83*
X1025168Y153909D03*
Y155877D03*
Y157846D03*
Y159814D03*
Y161783D03*
Y169657D03*
Y171625D03*
X1051940Y159814D03*
Y157846D03*
Y155877D03*
Y153909D03*
Y171625D03*
Y169657D03*
Y167688D03*
Y165720D03*
Y163751D03*
Y161783D03*
G54D65*
X696260Y43363D03*
G36*
G01X236452Y129690D02*
G02X249252Y116884I12800J-5D01*
G02X236452Y129680I0J12801D01*
G01X240952D01*
G03X249252Y137985I8300J5D01*
G03X240952Y129690I0J-8300D01*
G01X236452D01*
G37*
G36*
G01X516452D02*
G02X529252Y116884I12800J-5D01*
G02X516452Y129680I0J12801D01*
G01X520952D01*
G03X529252Y137985I8300J5D01*
G03X520952Y129690I0J-8300D01*
G01X516452D01*
G37*
G36*
G01X1213224Y174434D02*
G02X1226024Y161628I12800J-5D01*
G02X1213224Y174424I0J12801D01*
G01X1217724D01*
G03X1226024Y182729I8300J5D01*
G03X1217724Y174434I0J-8300D01*
G01X1213224D01*
G37*
G36*
G01Y399434D02*
G02X1226024Y386628I12800J-5D01*
G02X1213224Y399424I0J12801D01*
G01X1217724D01*
G03X1226024Y407729I8300J5D01*
G03X1217724Y399434I0J-8300D01*
G01X1213224D01*
G37*
G54D29*
G01X697575Y32000D02*
X697484Y31909D01*
Y27091D01*
X697575Y27000D01*
G01X701425Y32000D02*
X697575D01*
G01X752500Y27075D02*
Y22500D01*
X750500Y20500D01*
X700000D01*
X697575Y22925D01*
Y27000D01*
G01X752500Y27075D02*
X752925Y27500D01*
G01X803500Y261925D02*
Y259525D01*
G01X1100276Y93760D02*
X1095265D01*
X1095100Y93925D01*
G01D02*
X1091000D01*
G01D02*
Y89000D01*
G01X1083440Y95400D02*
Y93060D01*
X1087500Y89000D01*
X1091000D01*
G01X1168511Y341750D02*
Y335750D01*
G01D02*
Y328750D01*
G01X1165070D02*
X1168511D01*
G01X1190311Y341750D02*
Y335750D01*
G01D02*
Y328750D01*
G01X1193411D02*
X1190311D01*
G01X1184511Y335750D02*
X1180911D01*
X1179411Y334250D01*
G01Y337750D02*
X1179319D01*
X1177319Y335750D01*
X1174311D01*
G01X1184511Y328750D02*
X1181491D01*
X1179491Y330750D01*
X1179411D01*
G01X1174311Y328750D02*
X1177911D01*
X1179411Y327250D01*
G01X1180986Y349234D02*
Y346750D01*
G01D02*
X1180610Y346374D01*
Y342770D01*
X1181630Y341750D01*
X1184511D01*
G01X1177836Y349234D02*
Y346750D01*
G01D02*
X1178250Y346336D01*
Y342760D01*
X1177240Y341750D01*
X1174311D01*
G01X1168600Y484250D02*
Y478250D01*
G01D02*
Y471250D01*
G01D02*
X1165190D01*
G01X1190400Y484250D02*
Y478250D01*
G01D02*
Y471250D01*
G01D02*
X1193840D01*
G01X1181075Y489250D02*
X1180710Y488885D01*
Y485250D01*
X1181710Y484250D01*
X1184600D01*
G01X1177925Y489250D02*
X1178380Y488795D01*
Y485440D01*
X1177190Y484250D01*
X1174400D01*
G01X1179500Y476750D02*
X1181000Y478250D01*
X1184600D01*
G01X1179500Y480250D02*
X1179430D01*
X1177430Y478250D01*
X1174400D01*
G01X1179500Y469750D02*
X1181000Y471250D01*
X1184600D01*
G01X1174400D02*
X1177410D01*
X1179410Y473250D01*
X1179500D01*
G01X1181075Y489250D02*
Y491734D01*
G01X1177925Y489250D02*
Y491734D01*
X165350Y220098D03*
X162850D03*
Y227185D03*
Y230728D03*
X165350Y223642D03*
Y227185D03*
Y230728D03*
X162850Y223642D03*
G36*
G01X665064Y162208D02*
G02X665059Y136607I-5J-12800D01*
G02X665054Y162208I0J12801D01*
G01Y157708D01*
G03X665059Y141107I5J-8300D01*
G03X665064Y157708I0J8301D01*
G01Y162208D01*
G37*
G36*
G01X980064D02*
G02X980059Y136607I-5J-12800D01*
G02X980054Y162208I0J12801D01*
G01Y157708D01*
G03X980059Y141107I5J-8300D01*
G03X980064Y157708I0J8301D01*
G01Y162208D01*
G37*
G54D48*
X241740Y237000D03*
X234260D03*
X390260Y236500D03*
X397740D03*
X551240Y237500D03*
X543760D03*
X708721D03*
X701241D03*
X1028294Y188767D03*
X1020814D03*
X1028294Y199267D03*
X1020814D03*
X1083440Y95400D03*
X1075960D03*
X1096260Y82500D03*
X1098740Y199500D03*
X1091260D03*
X1103740Y82500D03*
G54D75*
X849000Y370200D03*
Y381800D03*
X867000Y370200D03*
Y381800D03*
X858000Y370200D03*
Y381800D03*
X876000Y370200D03*
Y381800D03*
X895000Y370200D03*
Y381800D03*
X885500Y370200D03*
Y381800D03*
X904500Y370200D03*
Y381800D03*
X914000Y370200D03*
Y381800D03*
X923500Y370200D03*
Y381800D03*
X933000Y370200D03*
Y381800D03*
X942500Y370200D03*
Y381800D03*
X952000Y370200D03*
Y381800D03*
X1025000Y131200D03*
Y142800D03*
X1068554Y127467D03*
Y139067D03*
X1161200Y160200D03*
Y171800D03*
X1140641Y205399D03*
Y193799D03*
G54D84*
X1070715Y150749D03*
Y174785D03*
X1073274Y150749D03*
X1075834D03*
X1078393D03*
X1073274Y174785D03*
X1075834D03*
X1078393D03*
G54D39*
X178819Y277204D03*
X193819D03*
X253819D03*
X268819D03*
X336299D03*
X351299D03*
X411299D03*
X426299D03*
X493780D03*
X508780D03*
X568780D03*
X583780D03*
X651261D03*
X666261D03*
X726261D03*
X741261D03*
G54D93*
X1240158Y57480D03*
Y521260D03*
G54D66*
X697441Y47300D03*
G54D58*
X700984Y41591D03*
G54D76*
X861622Y513070D03*
X904200D03*
G54D94*
X1147735Y124913D03*
G54D67*
X696260Y51237D03*
G54D49*
X268000Y220315D03*
X312500D03*
X357000D03*
X428500D03*
X472500D03*
X516500D03*
X578500D03*
X622500D03*
X666500D03*
X735981D03*
X779981D03*
X823981D03*
G54D85*
X1076164Y250442D03*
Y270442D03*
Y297942D03*
Y317942D03*
Y345442D03*
Y365442D03*
Y392942D03*
Y412942D03*
Y440442D03*
Y487942D03*
Y460442D03*
Y507942D03*
G54D59*
X699016Y41591D03*
G54D86*
X1100276Y93760D03*
Y101240D03*
X1109724D03*
Y97500D03*
Y93760D03*
G54D77*
X1011000Y98000D03*
X1151000Y90400D03*
G54D68*
X717985Y51000D03*
X741015D03*
G54D95*
X1138178Y166699D03*
G54D87*
X1089772Y132065D03*
Y139545D03*
X1132941Y131996D03*
Y124516D03*
X1123441Y131996D03*
Y124516D03*
X1152587Y131678D03*
Y139158D03*
X1166000Y140760D03*
Y148240D03*
G54D69*
X753314Y607542D03*
X766498Y602542D03*
X753420Y635687D03*
X766604Y630687D03*
X766498Y612542D03*
X766604Y640687D03*
X1096017Y607542D03*
X1082833Y602542D03*
Y612542D03*
X1096017Y635687D03*
X1082833Y630687D03*
Y640687D03*
G54D78*
X1011000Y118000D03*
Y108000D03*
X1161000Y90400D03*
X1171000D03*
G54D96*
X1183561Y130467D03*
Y156451D03*
G54D97*
X1183100Y176094D03*
Y212906D03*
G54D79*
X1041999Y162767D03*
G54D88*
X1116814Y260442D03*
Y307942D03*
Y355442D03*
Y402942D03*
Y450442D03*
Y497942D03*
G54D98*
X1176593Y307942D03*
X1182709D03*
X1176682Y450442D03*
X1182798D03*
G54D89*
X1077614Y545500D03*
X1104386D03*
G54D99*
X1170793Y307942D03*
X1188509D03*
X1170882Y450442D03*
X1188598D03*
M02*
